FILE_TYPE = MACRO_DRAWING;
SET COLOR_WIRE YELLOW;
SET COLOR_PROP ORANGE;
SET COLOR_DOT WHITE;
SET COLOR_ARC YELLOW;
SET COLOR_BODY GREEN;
SET COLOR_NOTE PURPLE;
SET PROP_DISPLAY VALUE;
SET PAGE_NUMBER P133;
FORCEADD Q_RES..1
(1625 2975);
FORCEPROP 1 LAST PART_NUMBER CS01002FB07
J 0
(1775 3000);
DISPLAY 0.319149 (1775 3000);
DISPLAY INVISIBLE (1775 3000);
FORCEPROP 1 LAST MATERIAL CHIP
J 0
(1775 3025);
DISPLAY 0.319149 (1775 3025);
FORCEPROP 1 LAST VALUE 10
J 2
(1800 2975);
DISPLAY 0.510638 (1800 2975);
FORCEPROP 1 LAST TOLERANCE 1%
J 0
(1825 2975);
DISPLAY 0.510638 (1825 2975);
FORCEPROP 1 LAST PACK_TYPE 0402LF
J 0
(1900 2975);
DISPLAY 0.510638 (1900 2975);
FORCEPROP 1 LAST WATTAGE 1/16W
J 2
(1950 3025);
DISPLAY 0.319149 (1950 3025);
FORCEPROP 1 LAST $LOCATION R777
J 0
(1425 2975);
DISPLAY 0.638298 (1425 2975);
FORCEPROP 1 LASTPIN (1525 2975) $PN 1
J 0
(1537 2987);
DISPLAY 0.787234 (1537 2987);
FORCEPROP 1 LASTPIN (1725 2975) $PN 2
J 0
(1687 2987);
DISPLAY 0.787234 (1687 2987);
FORCEPROP 2 LAST CDS_LIB pure_quanta
J 0
(1625 2975);
PAINT MONO (1625 2975);
DISPLAY INVISIBLE (1625 2975);
FORCEPROP 1 LAST PATH I10
J 0
(1575 3125);
DISPLAY 0.978723 (1575 3125);
PAINT WHITE (1575 3125);
DISPLAY INVISIBLE (1575 3125);
FORCEPROP 2 LAST CDS_LOCATION R777
J 0
(1575 3175);
DISPLAY 1.021277 (1575 3175);
DISPLAY INVISIBLE (1575 3175);
FORCEPROP 2 LAST $SEC 1
J 0
(1575 3175);
DISPLAY 0.680851 (1575 3175);
PAINT MONO (1575 3175);
DISPLAY INVISIBLE (1575 3175);
FORCEPROP 2 LAST CDS_SEC 1
J 0
(1575 3175);
DISPLAY 1.021277 (1575 3175);
DISPLAY INVISIBLE (1575 3175);
FORCEADD Q_CAP..1
R 2
(-125 3500);
FORCEPROP 1 LAST PART_NUMBER CH5104KEB02
J 2
(-175 3350);
DISPLAY 0.510638 (-175 3350);
DISPLAY INVISIBLE (-175 3350);
FORCEPROP 1 LAST PACK_TYPE C0402
J 2
(-175 3300);
DISPLAY 0.510638 (-175 3300);
FORCEPROP 1 LAST MATERIAL X6S
J 2
(-175 3400);
DISPLAY 0.510638 (-175 3400);
FORCEPROP 1 LAST VALUE 1UF
J 2
(-175 3550);
DISPLAY 0.510638 (-175 3550);
FORCEPROP 1 LAST VOLTAGE 25V
J 2
(-175 3500);
DISPLAY 0.510638 (-175 3500);
FORCEPROP 1 LAST TOLERANCE 10%
J 2
(-175 3450);
DISPLAY 0.510638 (-175 3450);
FORCEPROP 1 LAST $LOCATION C547
J 2
(-175 3600);
DISPLAY 0.978723 (-175 3600);
FORCEPROP 1 LASTPIN (-125 3600) $PN 1
J 2
(-135 3580);
DISPLAY 0.787234 (-135 3580);
FORCEPROP 1 LASTPIN (-125 3400) $PN 2
J 2
(-135 3380);
DISPLAY 0.787234 (-135 3380);
FORCEPROP 2 LAST CDS_LIB pure_quanta
J 2
(-125 3500);
PAINT MONO (-125 3500);
DISPLAY INVISIBLE (-125 3500);
FORCEPROP 1 LAST PATH I100
J 2
(-175 3650);
DISPLAY 0.978723 (-175 3650);
PAINT WHITE (-175 3650);
DISPLAY INVISIBLE (-175 3650);
FORCEPROP 2 LAST CDS_LOCATION C547
J 0
(-175 3700);
DISPLAY 1.021277 (-175 3700);
DISPLAY INVISIBLE (-175 3700);
FORCEPROP 2 LAST $SEC 1
J 0
(-175 3700);
DISPLAY 0.680851 (-175 3700);
PAINT MONO (-175 3700);
DISPLAY INVISIBLE (-175 3700);
FORCEPROP 2 LAST CDS_SEC 1
J 0
(-175 3700);
DISPLAY 1.021277 (-175 3700);
DISPLAY INVISIBLE (-175 3700);
FORCEADD UNIVERSAL_GND..1
(-125 3300);
FORCEPROP 3 LASTPIN (-125 3350) SIG_NAME GND\g
J 0
(-115 3360);
DISPLAY 0.659574 (-115 3360);
PAINT MONO (-115 3360);
DISPLAY INVISIBLE (-115 3360);
FORCEPROP 2 LAST CDS_LIB logical_power
J 0
(-125 3300);
PAINT MONO (-125 3300);
DISPLAY INVISIBLE (-125 3300);
FORCEPROP 1 LAST HDL_POWER GND
J 1
(-100 3225);
DISPLAY 0.872340 (-100 3225);
PAINT GREEN (-100 3225);
DISPLAY INVISIBLE (-100 3225);
FORCEPROP 1 LAST PATH I101
J 0
(-50 3300);
DISPLAY 0.872340 (-50 3300);
PAINT AQUA (-50 3300);
DISPLAY INVISIBLE (-50 3300);
FORCEADD Q_RES..2
(2650 2650);
FORCEPROP 1 LAST PART_NUMBER CS31002FB08
J 0
(2690 2525);
DISPLAY 0.510638 (2690 2525);
DISPLAY INVISIBLE (2690 2525);
FORCEPROP 1 LAST PACK_TYPE 0402LF
J 0
(2690 2475);
DISPLAY 0.638298 (2690 2475);
FORCEPROP 1 LAST TOLERANCE 1%
J 0
(2695 2675);
DISPLAY 0.638298 (2695 2675);
FORCEPROP 1 LAST VALUE 10K
J 0
(2695 2725);
DISPLAY 0.638298 (2695 2725);
FORCEPROP 1 LAST MATERIAL CHIP
J 0
(2690 2575);
DISPLAY 0.638298 (2690 2575);
FORCEPROP 1 LAST WATTAGE 1/16W
J 0
(2690 2625);
DISPLAY 0.638298 (2690 2625);
FORCEPROP 1 LAST $LOCATION R769
J 0
(2695 2775);
DISPLAY 0.978723 (2695 2775);
FORCEPROP 1 LASTPIN (2650 2750) $PN 1
J 0
(2655 2712);
DISPLAY 0.787234 (2655 2712);
FORCEPROP 1 LASTPIN (2650 2550) $PN 2
J 0
(2655 2560);
DISPLAY 0.787234 (2655 2560);
FORCEPROP 2 LAST CDS_LIB pure_quanta
J 0
(2650 2650);
PAINT MONO (2650 2650);
DISPLAY INVISIBLE (2650 2650);
FORCEPROP 1 LAST PATH I102
J 0
(2700 2825);
DISPLAY 0.978723 (2700 2825);
PAINT WHITE (2700 2825);
DISPLAY INVISIBLE (2700 2825);
FORCEPROP 2 LAST CDS_LOCATION R769
J 2
(2700 2875);
DISPLAY 1.021277 (2700 2875);
DISPLAY INVISIBLE (2700 2875);
FORCEPROP 2 LAST $SEC 1
J 2
(2700 2875);
DISPLAY 0.680851 (2700 2875);
PAINT MONO (2700 2875);
DISPLAY INVISIBLE (2700 2875);
FORCEPROP 2 LAST CDS_SEC 1
J 2
(2700 2875);
DISPLAY 1.021277 (2700 2875);
DISPLAY INVISIBLE (2700 2875);
FORCEADD UNIVERSAL_GND..1
(2650 2425);
FORCEPROP 3 LASTPIN (2650 2475) SIG_NAME GND\g
J 0
(2660 2485);
DISPLAY 0.659574 (2660 2485);
PAINT MONO (2660 2485);
DISPLAY INVISIBLE (2660 2485);
FORCEPROP 2 LAST CDS_LIB logical_power
J 0
(2650 2425);
PAINT MONO (2650 2425);
DISPLAY INVISIBLE (2650 2425);
FORCEPROP 1 LAST HDL_POWER GND
J 1
(2675 2350);
DISPLAY 0.872340 (2675 2350);
PAINT GREEN (2675 2350);
DISPLAY INVISIBLE (2675 2350);
FORCEPROP 1 LAST PATH I103
J 0
(2725 2425);
DISPLAY 0.872340 (2725 2425);
PAINT AQUA (2725 2425);
DISPLAY INVISIBLE (2725 2425);
FORCEADD UNIVERSAL_GND..1
(1825 1325);
FORCEPROP 3 LASTPIN (1825 1375) SIG_NAME GND\g
J 0
(1835 1385);
DISPLAY 0.659574 (1835 1385);
PAINT MONO (1835 1385);
DISPLAY INVISIBLE (1835 1385);
FORCEPROP 2 LAST CDS_LIB logical_power
J 0
(1825 1325);
PAINT MONO (1825 1325);
DISPLAY INVISIBLE (1825 1325);
FORCEPROP 1 LAST HDL_POWER GND
J 1
(1850 1250);
DISPLAY 0.872340 (1850 1250);
PAINT GREEN (1850 1250);
DISPLAY INVISIBLE (1850 1250);
FORCEPROP 1 LAST PATH I104
J 0
(1900 1325);
DISPLAY 0.872340 (1900 1325);
PAINT AQUA (1900 1325);
DISPLAY INVISIBLE (1900 1325);
FORCEADD Q_CAP..1
(1825 1525);
FORCEPROP 1 LAST PART_NUMBER CH5104KEB02
J 0
(1875 1375);
DISPLAY 0.510638 (1875 1375);
DISPLAY INVISIBLE (1875 1375);
FORCEPROP 1 LAST VOLTAGE 25V
J 0
(1875 1525);
DISPLAY 0.510638 (1875 1525);
FORCEPROP 1 LAST MATERIAL X6S
J 0
(1875 1425);
DISPLAY 0.510638 (1875 1425);
FORCEPROP 1 LAST TOLERANCE 10%
J 0
(1875 1475);
DISPLAY 0.510638 (1875 1475);
FORCEPROP 1 LAST VALUE 1UF
J 0
(1875 1575);
DISPLAY 0.510638 (1875 1575);
FORCEPROP 1 LAST PACK_TYPE C0402
J 0
(1875 1325);
DISPLAY 0.510638 (1875 1325);
FORCEPROP 1 LAST $LOCATION C551
J 0
(1875 1625);
DISPLAY 0.978723 (1875 1625);
FORCEPROP 1 LASTPIN (1825 1625) $PN 1
J 0
(1835 1605);
DISPLAY 0.787234 (1835 1605);
FORCEPROP 1 LASTPIN (1825 1425) $PN 2
J 0
(1835 1405);
DISPLAY 0.787234 (1835 1405);
FORCEPROP 2 LAST CDS_LIB pure_quanta
J 0
(1825 1525);
PAINT MONO (1825 1525);
DISPLAY INVISIBLE (1825 1525);
FORCEPROP 1 LAST PATH I105
J 0
(1875 1675);
DISPLAY 0.978723 (1875 1675);
PAINT WHITE (1875 1675);
DISPLAY INVISIBLE (1875 1675);
FORCEPROP 2 LAST CDS_LOCATION C551
J 0
(1875 1725);
DISPLAY 1.021277 (1875 1725);
DISPLAY INVISIBLE (1875 1725);
FORCEPROP 2 LAST $SEC 1
J 0
(1875 1725);
DISPLAY 0.680851 (1875 1725);
PAINT MONO (1875 1725);
DISPLAY INVISIBLE (1875 1725);
FORCEPROP 2 LAST CDS_SEC 1
J 0
(1875 1725);
DISPLAY 1.021277 (1875 1725);
DISPLAY INVISIBLE (1875 1725);
FORCEADD OFFPAGE..1
(-1225 -575);
FORCEPROP 2 LAST $XR0 131 
J 0
(-1507 -575);
DISPLAY 0.638298 (-1507 -575);
PAINT MONO (-1507 -575);
FORCEPROP 2 LAST CDS_LIB standard
J 0
(-1225 -575);
PAINT MONO (-1225 -575);
DISPLAY INVISIBLE (-1225 -575);
FORCEPROP 1 LAST OFFPAGE TRUE
J 0
(-900 -700);
DISPLAY 0.872340 (-900 -700);
PAINT GREEN (-900 -700);
DISPLAY INVISIBLE (-900 -700);
FORCEPROP 1 LAST COMMENT_BODY TRUE
J 0
(-1100 -675);
DISPLAY 0.872340 (-1100 -675);
PAINT GREEN (-1100 -675);
DISPLAY INVISIBLE (-1100 -675);
FORCEPROP 2 LAST PATH I106
J 0
(-1500 -525);
DISPLAY 1.021277 (-1500 -525);
DISPLAY INVISIBLE (-1500 -525);
FORCEADD UNIVERSAL_POWER..1
(-125 50);
FORCEPROP 3 LASTPIN (-125 0) SIG_NAME P3V3_AUX\g
J 0
(-115 10);
DISPLAY 0.659574 (-115 10);
PAINT MONO (-115 10);
DISPLAY INVISIBLE (-115 10);
FORCEPROP 1 LAST HDL_POWER P3V3_AUX
J 1
(-125 100);
DISPLAY 0.872340 (-125 100);
PAINT GREEN (-125 100);
FORCEPROP 2 LAST CDS_LIB logical_power
J 0
(-125 50);
PAINT MONO (-125 50);
DISPLAY INVISIBLE (-125 50);
FORCEPROP 1 LAST PATH I109
J 0
(-75 75);
DISPLAY 0.872340 (-75 75);
PAINT AQUA (-75 75);
DISPLAY INVISIBLE (-75 75);
FORCEADD UNIVERSAL_POWER..1
(725 3750);
FORCEPROP 3 LASTPIN (725 3700) SIG_NAME P1V8_PCH_AUX\g
J 0
(735 3710);
DISPLAY 0.659574 (735 3710);
PAINT MONO (735 3710);
DISPLAY INVISIBLE (735 3710);
FORCEPROP 1 LAST HDL_POWER P1V8_PCH_AUX
J 1
(725 3800);
DISPLAY 0.872340 (725 3800);
PAINT GREEN (725 3800);
FORCEPROP 2 LAST CDS_LIB logical_power
J 0
(725 3750);
PAINT MONO (725 3750);
DISPLAY INVISIBLE (725 3750);
FORCEPROP 1 LAST PATH I11
J 0
(775 3775);
DISPLAY 0.872340 (775 3775);
PAINT AQUA (775 3775);
DISPLAY INVISIBLE (775 3775);
FORCEADD Q_RES..2
(-125 -250);
FORCEPROP 1 LAST PART_NUMBER CS21002FB06
J 0
(-85 -375);
DISPLAY 0.404255 (-85 -375);
DISPLAY INVISIBLE (-85 -375);
FORCEPROP 1 LAST PACK_TYPE 0402LF
J 0
(-85 -375);
DISPLAY 0.510638 (-85 -375);
FORCEPROP 1 LAST VALUE 1K
J 0
(-80 -175);
DISPLAY 0.510638 (-80 -175);
FORCEPROP 1 LAST TOLERANCE 1%
J 0
(-80 -225);
DISPLAY 0.510638 (-80 -225);
FORCEPROP 1 LAST MATERIAL EMPTY
J 0
(-85 -325);
DISPLAY 0.510638 (-85 -325);
PAINT RED (-85 -325);
FORCEPROP 1 LAST WATTAGE 1/16W
J 0
(-85 -275);
DISPLAY 0.510638 (-85 -275);
FORCEPROP 1 LAST $LOCATION R766
J 0
(-80 -125);
DISPLAY 0.978723 (-80 -125);
FORCEPROP 1 LASTPIN (-125 -150) $PN 1
J 0
(-120 -188);
DISPLAY 0.787234 (-120 -188);
FORCEPROP 1 LASTPIN (-125 -350) $PN 2
J 0
(-120 -340);
DISPLAY 0.787234 (-120 -340);
FORCEPROP 2 LAST CDS_LIB pure_quanta
J 0
(-125 -250);
PAINT MONO (-125 -250);
DISPLAY INVISIBLE (-125 -250);
FORCEPROP 1 LAST PATH I111
J 0
(-75 -75);
DISPLAY 0.978723 (-75 -75);
PAINT WHITE (-75 -75);
DISPLAY INVISIBLE (-75 -75);
FORCEPROP 2 LAST CDS_LOCATION R766
J 0
(-75 -25);
DISPLAY 1.021277 (-75 -25);
DISPLAY INVISIBLE (-75 -25);
FORCEPROP 2 LAST $SEC 1
J 0
(-75 -25);
DISPLAY 0.680851 (-75 -25);
PAINT MONO (-75 -25);
DISPLAY INVISIBLE (-75 -25);
FORCEPROP 2 LAST CDS_SEC 1
J 0
(-75 -25);
DISPLAY 1.021277 (-75 -25);
DISPLAY INVISIBLE (-75 -25);
FORCEADD Q_RES..2
(300 -250);
FORCEPROP 1 LAST PART_NUMBER CS21002FB06
J 0
(340 -425);
DISPLAY 0.510638 (340 -425);
DISPLAY INVISIBLE (340 -425);
FORCEPROP 1 LAST WATTAGE 1/16W
J 0
(340 -275);
DISPLAY 0.510638 (340 -275);
FORCEPROP 1 LAST TOLERANCE 1%
J 0
(345 -225);
DISPLAY 0.510638 (345 -225);
FORCEPROP 1 LAST VALUE 1K
J 0
(345 -175);
DISPLAY 0.510638 (345 -175);
FORCEPROP 1 LAST MATERIAL CHIP
J 0
(340 -325);
DISPLAY 0.510638 (340 -325);
FORCEPROP 1 LAST PACK_TYPE 0402LF
J 0
(340 -375);
DISPLAY 0.510638 (340 -375);
FORCEPROP 1 LAST $LOCATION R768
J 0
(345 -125);
DISPLAY 0.978723 (345 -125);
FORCEPROP 1 LASTPIN (300 -150) $PN 1
J 0
(305 -188);
DISPLAY 0.787234 (305 -188);
FORCEPROP 1 LASTPIN (300 -350) $PN 2
J 0
(305 -340);
DISPLAY 0.787234 (305 -340);
FORCEPROP 2 LAST CDS_LIB pure_quanta
J 0
(300 -250);
PAINT MONO (300 -250);
DISPLAY INVISIBLE (300 -250);
FORCEPROP 1 LAST PATH I112
J 0
(350 -75);
DISPLAY 0.978723 (350 -75);
PAINT WHITE (350 -75);
DISPLAY INVISIBLE (350 -75);
FORCEPROP 2 LAST CDS_LOCATION R768
J 0
(350 -25);
DISPLAY 1.021277 (350 -25);
DISPLAY INVISIBLE (350 -25);
FORCEPROP 2 LAST $SEC 1
J 0
(350 -25);
DISPLAY 0.680851 (350 -25);
PAINT MONO (350 -25);
DISPLAY INVISIBLE (350 -25);
FORCEPROP 2 LAST CDS_SEC 1
J 0
(350 -25);
DISPLAY 1.021277 (350 -25);
DISPLAY INVISIBLE (350 -25);
FORCEADD Q_RES..2
(100 -250);
FORCEPROP 1 LAST PART_NUMBER CS21002FB06
J 0
(140 -375);
DISPLAY 0.404255 (140 -375);
DISPLAY INVISIBLE (140 -375);
FORCEPROP 1 LAST PACK_TYPE 0402LF
J 0
(140 -375);
DISPLAY 0.510638 (140 -375);
FORCEPROP 1 LAST MATERIAL CHIP
J 0
(140 -325);
DISPLAY 0.510638 (140 -325);
FORCEPROP 1 LAST WATTAGE 1/16W
J 0
(140 -275);
DISPLAY 0.510638 (140 -275);
FORCEPROP 1 LAST TOLERANCE 1%
J 0
(145 -225);
DISPLAY 0.510638 (145 -225);
FORCEPROP 1 LAST VALUE 1K
J 0
(145 -175);
DISPLAY 0.510638 (145 -175);
FORCEPROP 1 LAST $LOCATION R767
J 0
(145 -125);
DISPLAY 0.978723 (145 -125);
FORCEPROP 1 LASTPIN (100 -150) $PN 1
J 0
(105 -188);
DISPLAY 0.787234 (105 -188);
FORCEPROP 1 LASTPIN (100 -350) $PN 2
J 0
(105 -340);
DISPLAY 0.787234 (105 -340);
FORCEPROP 2 LAST CDS_LIB pure_quanta
J 0
(100 -250);
PAINT MONO (100 -250);
DISPLAY INVISIBLE (100 -250);
FORCEPROP 1 LAST PATH I113
J 0
(150 -75);
DISPLAY 0.978723 (150 -75);
PAINT WHITE (150 -75);
DISPLAY INVISIBLE (150 -75);
FORCEPROP 2 LAST CDS_LOCATION R767
J 0
(150 -25);
DISPLAY 1.021277 (150 -25);
DISPLAY INVISIBLE (150 -25);
FORCEPROP 2 LAST $SEC 1
J 0
(150 -25);
DISPLAY 0.680851 (150 -25);
PAINT MONO (150 -25);
DISPLAY INVISIBLE (150 -25);
FORCEPROP 2 LAST CDS_SEC 1
J 0
(150 -25);
DISPLAY 1.021277 (150 -25);
DISPLAY INVISIBLE (150 -25);
FORCEADD OFFPAGE..2
(2050 -725);
FORCEPROP 2 LAST $XR0 215 
J 0
(2239 -725);
DISPLAY 0.638298 (2239 -725);
PAINT MONO (2239 -725);
FORCEPROP 2 LAST CDS_LIB standard
J 0
(2050 -725);
PAINT MONO (2050 -725);
DISPLAY INVISIBLE (2050 -725);
FORCEPROP 1 LAST OFFPAGE TRUE
J 0
(2375 -850);
DISPLAY 0.872340 (2375 -850);
PAINT GREEN (2375 -850);
DISPLAY INVISIBLE (2375 -850);
FORCEPROP 1 LAST COMMENT_BODY TRUE
J 0
(2005 -820);
DISPLAY 0.872340 (2005 -820);
PAINT GREEN (2005 -820);
DISPLAY INVISIBLE (2005 -820);
FORCEPROP 2 LAST PATH I115
J 0
(2225 -650);
DISPLAY 1.021277 (2225 -650);
DISPLAY INVISIBLE (2225 -650);
FORCEADD OFFPAGE..1
(-1225 -800);
FORCEPROP 2 LAST $XR0 131 
J 0
(-1507 -800);
DISPLAY 0.638298 (-1507 -800);
PAINT MONO (-1507 -800);
FORCEPROP 2 LAST CDS_LIB standard
J 0
(-1225 -800);
PAINT MONO (-1225 -800);
DISPLAY INVISIBLE (-1225 -800);
FORCEPROP 1 LAST OFFPAGE TRUE
J 0
(-900 -925);
DISPLAY 0.872340 (-900 -925);
PAINT GREEN (-900 -925);
DISPLAY INVISIBLE (-900 -925);
FORCEPROP 1 LAST COMMENT_BODY TRUE
J 0
(-1100 -900);
DISPLAY 0.872340 (-1100 -900);
PAINT GREEN (-1100 -900);
DISPLAY INVISIBLE (-1100 -900);
FORCEPROP 2 LAST PATH I116
J 0
(-1500 -750);
DISPLAY 1.021277 (-1500 -750);
DISPLAY INVISIBLE (-1500 -750);
FORCEADD Q_RES..1
(625 -875);
FORCEPROP 1 LAST PART_NUMBER CS21002FB06
J 0
(750 -850);
DISPLAY 0.319149 (750 -850);
DISPLAY INVISIBLE (750 -850);
FORCEPROP 1 LAST MATERIAL CHIP
J 0
(750 -825);
DISPLAY 0.319149 (750 -825);
FORCEPROP 1 LAST PACK_TYPE 0402LF
J 0
(875 -875);
DISPLAY 0.510638 (875 -875);
FORCEPROP 1 LAST WATTAGE 1/16W
J 2
(925 -825);
DISPLAY 0.319149 (925 -825);
FORCEPROP 1 LAST TOLERANCE 1%
J 0
(800 -875);
DISPLAY 0.510638 (800 -875);
FORCEPROP 1 LAST VALUE 1K
J 2
(775 -875);
DISPLAY 0.510638 (775 -875);
FORCEPROP 1 LAST $LOCATION R772
J 0
(400 -875);
DISPLAY 0.638298 (400 -875);
FORCEPROP 1 LASTPIN (525 -875) $PN 1
J 0
(537 -863);
DISPLAY 0.787234 (537 -863);
FORCEPROP 1 LASTPIN (725 -875) $PN 2
J 0
(687 -863);
DISPLAY 0.787234 (687 -863);
FORCEPROP 2 LAST CDS_LIB pure_quanta
J 0
(625 -875);
PAINT MONO (625 -875);
DISPLAY INVISIBLE (625 -875);
FORCEPROP 1 LAST PATH I118
J 0
(575 -725);
DISPLAY 0.978723 (575 -725);
PAINT WHITE (575 -725);
DISPLAY INVISIBLE (575 -725);
FORCEPROP 2 LAST CDS_LOCATION R772
J 0
(575 -675);
DISPLAY 1.021277 (575 -675);
DISPLAY INVISIBLE (575 -675);
FORCEPROP 2 LAST $SEC 1
J 0
(575 -675);
DISPLAY 0.680851 (575 -675);
PAINT MONO (575 -675);
DISPLAY INVISIBLE (575 -675);
FORCEPROP 2 LAST CDS_SEC 1
J 0
(575 -675);
DISPLAY 1.021277 (575 -675);
DISPLAY INVISIBLE (575 -675);
FORCEADD UNIVERSAL_GND..1
(725 1500);
FORCEPROP 3 LASTPIN (725 1550) SIG_NAME GND\g
J 0
(735 1560);
DISPLAY 0.659574 (735 1560);
PAINT MONO (735 1560);
DISPLAY INVISIBLE (735 1560);
FORCEPROP 2 LAST CDS_LIB logical_power
J 0
(725 1500);
PAINT MONO (725 1500);
DISPLAY INVISIBLE (725 1500);
FORCEPROP 1 LAST HDL_POWER GND
J 1
(750 1425);
DISPLAY 0.872340 (750 1425);
PAINT GREEN (750 1425);
DISPLAY INVISIBLE (750 1425);
FORCEPROP 1 LAST PATH I12
J 0
(800 1500);
DISPLAY 0.872340 (800 1500);
PAINT AQUA (800 1500);
DISPLAY INVISIBLE (800 1500);
FORCEADD Q_RES..1
(625 -800);
FORCEPROP 1 LAST PART_NUMBER CS21002FB06
J 0
(750 -775);
DISPLAY 0.319149 (750 -775);
DISPLAY INVISIBLE (750 -775);
FORCEPROP 1 LAST TOLERANCE 1%
J 0
(800 -800);
DISPLAY 0.510638 (800 -800);
FORCEPROP 1 LAST WATTAGE 1/16W
J 2
(925 -750);
DISPLAY 0.319149 (925 -750);
FORCEPROP 1 LAST VALUE 1K
J 2
(775 -800);
DISPLAY 0.510638 (775 -800);
FORCEPROP 1 LAST PACK_TYPE 0402LF
J 0
(875 -800);
DISPLAY 0.510638 (875 -800);
FORCEPROP 1 LAST MATERIAL CHIP
J 0
(750 -750);
DISPLAY 0.319149 (750 -750);
FORCEPROP 1 LAST $LOCATION R771
J 0
(400 -800);
DISPLAY 0.638298 (400 -800);
FORCEPROP 1 LASTPIN (525 -800) $PN 1
J 0
(537 -788);
DISPLAY 0.787234 (537 -788);
FORCEPROP 1 LASTPIN (725 -800) $PN 2
J 0
(687 -788);
DISPLAY 0.787234 (687 -788);
FORCEPROP 2 LAST CDS_LIB pure_quanta
J 0
(625 -800);
PAINT MONO (625 -800);
DISPLAY INVISIBLE (625 -800);
FORCEPROP 1 LAST PATH I120
J 0
(575 -650);
DISPLAY 0.978723 (575 -650);
PAINT WHITE (575 -650);
DISPLAY INVISIBLE (575 -650);
FORCEPROP 2 LAST CDS_LOCATION R771
J 0
(575 -600);
DISPLAY 1.021277 (575 -600);
DISPLAY INVISIBLE (575 -600);
FORCEPROP 2 LAST $SEC 1
J 0
(575 -600);
DISPLAY 0.680851 (575 -600);
PAINT MONO (575 -600);
DISPLAY INVISIBLE (575 -600);
FORCEPROP 2 LAST CDS_SEC 1
J 0
(575 -600);
DISPLAY 1.021277 (575 -600);
DISPLAY INVISIBLE (575 -600);
FORCEADD OFFPAGE..2
(2050 -800);
FORCEPROP 2 LAST $XR1 185 
J 0
(2359 -800);
DISPLAY 0.638298 (2359 -800);
PAINT MONO (2359 -800);
FORCEPROP 2 LAST $XR0 198 
J 0
(2239 -800);
DISPLAY 0.638298 (2239 -800);
PAINT MONO (2239 -800);
FORCEPROP 2 LAST CDS_LIB standard
J 0
(2050 -800);
PAINT MONO (2050 -800);
DISPLAY INVISIBLE (2050 -800);
FORCEPROP 1 LAST OFFPAGE TRUE
J 0
(2375 -925);
DISPLAY 0.872340 (2375 -925);
PAINT GREEN (2375 -925);
DISPLAY INVISIBLE (2375 -925);
FORCEPROP 1 LAST COMMENT_BODY TRUE
J 0
(2005 -895);
DISPLAY 0.872340 (2005 -895);
PAINT GREEN (2005 -895);
DISPLAY INVISIBLE (2005 -895);
FORCEPROP 2 LAST PATH I121
J 0
(2225 -725);
DISPLAY 1.021277 (2225 -725);
DISPLAY INVISIBLE (2225 -725);
FORCEADD OFFPAGE..1
(-1225 -950);
FORCEPROP 2 LAST $XR0 131 
J 0
(-1507 -950);
DISPLAY 0.638298 (-1507 -950);
PAINT MONO (-1507 -950);
FORCEPROP 2 LAST CDS_LIB standard
J 0
(-1225 -950);
PAINT MONO (-1225 -950);
DISPLAY INVISIBLE (-1225 -950);
FORCEPROP 1 LAST OFFPAGE TRUE
J 0
(-900 -1075);
DISPLAY 0.872340 (-900 -1075);
PAINT GREEN (-900 -1075);
DISPLAY INVISIBLE (-900 -1075);
FORCEPROP 1 LAST COMMENT_BODY TRUE
J 0
(-1100 -1050);
DISPLAY 0.872340 (-1100 -1050);
PAINT GREEN (-1100 -1050);
DISPLAY INVISIBLE (-1100 -1050);
FORCEPROP 2 LAST PATH I122
J 0
(-1500 -900);
DISPLAY 1.021277 (-1500 -900);
DISPLAY INVISIBLE (-1500 -900);
FORCEADD OFFPAGE..2
(2050 -950);
FORCEPROP 2 LAST $XR2 185 
J 0
(2479 -950);
DISPLAY 0.638298 (2479 -950);
PAINT MONO (2479 -950);
FORCEPROP 2 LAST $XR1 205 
J 0
(2359 -950);
DISPLAY 0.638298 (2359 -950);
PAINT MONO (2359 -950);
FORCEPROP 2 LAST $XR0 198 
J 0
(2239 -950);
DISPLAY 0.638298 (2239 -950);
PAINT MONO (2239 -950);
FORCEPROP 2 LAST CDS_LIB standard
J 0
(2050 -950);
PAINT MONO (2050 -950);
DISPLAY INVISIBLE (2050 -950);
FORCEPROP 1 LAST OFFPAGE TRUE
J 0
(2375 -1075);
DISPLAY 0.872340 (2375 -1075);
PAINT GREEN (2375 -1075);
DISPLAY INVISIBLE (2375 -1075);
FORCEPROP 1 LAST COMMENT_BODY TRUE
J 0
(2005 -1045);
DISPLAY 0.872340 (2005 -1045);
PAINT GREEN (2005 -1045);
DISPLAY INVISIBLE (2005 -1045);
FORCEPROP 2 LAST PATH I123
J 0
(2225 -875);
DISPLAY 1.021277 (2225 -875);
DISPLAY INVISIBLE (2225 -875);
FORCEADD Q_RES..1
(625 -950);
FORCEPROP 1 LAST PART_NUMBER CS21002FB06
J 0
(750 -925);
DISPLAY 0.319149 (750 -925);
DISPLAY INVISIBLE (750 -925);
FORCEPROP 1 LAST VALUE 1K
J 2
(775 -950);
DISPLAY 0.510638 (775 -950);
FORCEPROP 1 LAST TOLERANCE 1%
J 0
(800 -950);
DISPLAY 0.510638 (800 -950);
FORCEPROP 1 LAST WATTAGE 1/16W
J 2
(925 -900);
DISPLAY 0.319149 (925 -900);
FORCEPROP 1 LAST PACK_TYPE 0402LF
J 0
(875 -950);
DISPLAY 0.510638 (875 -950);
FORCEPROP 1 LAST MATERIAL CHIP
J 0
(750 -900);
DISPLAY 0.319149 (750 -900);
FORCEPROP 1 LAST $LOCATION R773
J 0
(400 -950);
DISPLAY 0.638298 (400 -950);
FORCEPROP 1 LASTPIN (525 -950) $PN 1
J 0
(537 -938);
DISPLAY 0.787234 (537 -938);
FORCEPROP 1 LASTPIN (725 -950) $PN 2
J 0
(687 -938);
DISPLAY 0.787234 (687 -938);
FORCEPROP 2 LAST CDS_LIB pure_quanta
J 0
(625 -950);
PAINT MONO (625 -950);
DISPLAY INVISIBLE (625 -950);
FORCEPROP 1 LAST PATH I124
J 0
(575 -800);
DISPLAY 0.978723 (575 -800);
PAINT WHITE (575 -800);
DISPLAY INVISIBLE (575 -800);
FORCEPROP 2 LAST CDS_LOCATION R773
J 0
(575 -750);
DISPLAY 1.021277 (575 -750);
DISPLAY INVISIBLE (575 -750);
FORCEPROP 2 LAST $SEC 1
J 0
(575 -750);
DISPLAY 0.680851 (575 -750);
PAINT MONO (575 -750);
DISPLAY INVISIBLE (575 -750);
FORCEPROP 2 LAST CDS_SEC 1
J 0
(575 -750);
DISPLAY 1.021277 (575 -750);
DISPLAY INVISIBLE (575 -750);
FORCEADD UNIVERSAL_GND..1
(-125 -1475);
FORCEPROP 3 LASTPIN (-125 -1425) SIG_NAME GND\g
J 0
(-115 -1415);
DISPLAY 0.659574 (-115 -1415);
PAINT MONO (-115 -1415);
DISPLAY INVISIBLE (-115 -1415);
FORCEPROP 2 LAST CDS_LIB logical_power
J 0
(-125 -1475);
PAINT MONO (-125 -1475);
DISPLAY INVISIBLE (-125 -1475);
FORCEPROP 1 LAST HDL_POWER GND
J 1
(-100 -1550);
DISPLAY 0.872340 (-100 -1550);
PAINT GREEN (-100 -1550);
DISPLAY INVISIBLE (-100 -1550);
FORCEPROP 1 LAST PATH I126
J 0
(-50 -1475);
DISPLAY 0.872340 (-50 -1475);
PAINT AQUA (-50 -1475);
DISPLAY INVISIBLE (-50 -1475);
FORCEADD UNIVERSAL_GND..1
(100 -1475);
FORCEPROP 3 LASTPIN (100 -1425) SIG_NAME GND\g
J 0
(110 -1415);
DISPLAY 0.659574 (110 -1415);
PAINT MONO (110 -1415);
DISPLAY INVISIBLE (110 -1415);
FORCEPROP 2 LAST CDS_LIB logical_power
J 0
(100 -1475);
PAINT MONO (100 -1475);
DISPLAY INVISIBLE (100 -1475);
FORCEPROP 1 LAST HDL_POWER GND
J 1
(125 -1550);
DISPLAY 0.872340 (125 -1550);
PAINT GREEN (125 -1550);
DISPLAY INVISIBLE (125 -1550);
FORCEPROP 1 LAST PATH I128
J 0
(175 -1475);
DISPLAY 0.872340 (175 -1475);
PAINT AQUA (175 -1475);
DISPLAY INVISIBLE (175 -1475);
FORCEADD Q_CAP..1
(100 -1225);
FORCEPROP 1 LAST PART_NUMBER CH4104K1B00
J 0
(150 -1375);
DISPLAY 0.510638 (150 -1375);
DISPLAY INVISIBLE (150 -1375);
FORCEPROP 1 LAST VALUE 0.1UF
J 0
(150 -1175);
DISPLAY 0.510638 (150 -1175);
FORCEPROP 1 LAST VOLTAGE 25V
J 0
(150 -1225);
DISPLAY 0.510638 (150 -1225);
FORCEPROP 1 LAST PACK_TYPE 0402
J 0
(150 -1425);
DISPLAY 0.510638 (150 -1425);
FORCEPROP 1 LAST MATERIAL X7R
J 0
(150 -1325);
DISPLAY 0.510638 (150 -1325);
FORCEPROP 1 LAST TOLERANCE 10%
J 0
(150 -1275);
DISPLAY 0.510638 (150 -1275);
FORCEPROP 1 LAST $LOCATION C549
J 0
(150 -1125);
DISPLAY 0.978723 (150 -1125);
FORCEPROP 1 LASTPIN (100 -1125) $PN 1
J 0
(110 -1145);
DISPLAY 0.787234 (110 -1145);
FORCEPROP 1 LASTPIN (100 -1325) $PN 2
J 0
(110 -1345);
DISPLAY 0.787234 (110 -1345);
FORCEPROP 2 LAST CDS_LIB pure_quanta
J 0
(100 -1225);
PAINT MONO (100 -1225);
DISPLAY INVISIBLE (100 -1225);
FORCEPROP 1 LAST PATH I129
J 0
(150 -1075);
DISPLAY 0.978723 (150 -1075);
PAINT WHITE (150 -1075);
DISPLAY INVISIBLE (150 -1075);
FORCEPROP 2 LAST CDS_LOCATION C549
J 0
(150 -1025);
DISPLAY 1.021277 (150 -1025);
DISPLAY INVISIBLE (150 -1025);
FORCEPROP 2 LAST $SEC 1
J 0
(150 -1025);
DISPLAY 0.680851 (150 -1025);
PAINT MONO (150 -1025);
DISPLAY INVISIBLE (150 -1025);
FORCEPROP 2 LAST CDS_SEC 1
J 0
(150 -1025);
DISPLAY 1.021277 (150 -1025);
DISPLAY INVISIBLE (150 -1025);
FORCEADD OFFPAGE..2
(3700 2325);
FORCEPROP 2 LAST $XR0 131 
J 0
(3889 2325);
DISPLAY 0.638298 (3889 2325);
PAINT MONO (3889 2325);
FORCEPROP 2 LAST CDS_LIB standard
J 0
(3700 2325);
DISPLAY INVISIBLE (3700 2325);
FORCEPROP 1 LAST OFFPAGE TRUE
J 0
(4025 2200);
DISPLAY 0.872340 (4025 2200);
PAINT GREEN (4025 2200);
DISPLAY INVISIBLE (4025 2200);
FORCEPROP 1 LAST COMMENT_BODY TRUE
J 0
(3655 2230);
DISPLAY 0.872340 (3655 2230);
PAINT GREEN (3655 2230);
DISPLAY INVISIBLE (3655 2230);
FORCEPROP 2 LAST PATH I13
J 0
(3875 2400);
DISPLAY 1.021277 (3875 2400);
DISPLAY INVISIBLE (3875 2400);
FORCEADD Q_CAP..1
R 2
(-125 -1225);
FORCEPROP 1 LAST PART_NUMBER CH4104K1B00
J 2
(-175 -1375);
DISPLAY 0.510638 (-175 -1375);
DISPLAY INVISIBLE (-175 -1375);
FORCEPROP 1 LAST PACK_TYPE 0402
J 2
(-175 -1425);
DISPLAY 0.510638 (-175 -1425);
FORCEPROP 1 LAST TOLERANCE 10%
J 2
(-175 -1275);
DISPLAY 0.510638 (-175 -1275);
FORCEPROP 1 LAST VALUE 0.1UF
J 2
(-175 -1175);
DISPLAY 0.510638 (-175 -1175);
FORCEPROP 1 LAST VOLTAGE 25V
J 2
(-175 -1225);
DISPLAY 0.510638 (-175 -1225);
FORCEPROP 1 LAST MATERIAL X7R
J 2
(-175 -1325);
DISPLAY 0.510638 (-175 -1325);
FORCEPROP 1 LAST $LOCATION C548
J 2
(-175 -1125);
DISPLAY 0.978723 (-175 -1125);
FORCEPROP 1 LASTPIN (-125 -1125) $PN 1
J 2
(-135 -1145);
DISPLAY 0.787234 (-135 -1145);
FORCEPROP 1 LASTPIN (-125 -1325) $PN 2
J 2
(-135 -1345);
DISPLAY 0.787234 (-135 -1345);
FORCEPROP 2 LAST CDS_LIB pure_quanta
J 2
(-125 -1225);
PAINT MONO (-125 -1225);
DISPLAY INVISIBLE (-125 -1225);
FORCEPROP 1 LAST PATH I130
J 2
(-175 -1075);
DISPLAY 0.978723 (-175 -1075);
PAINT WHITE (-175 -1075);
DISPLAY INVISIBLE (-175 -1075);
FORCEPROP 2 LAST CDS_LOCATION C548
J 0
(-175 -1025);
DISPLAY 1.021277 (-175 -1025);
DISPLAY INVISIBLE (-175 -1025);
FORCEPROP 2 LAST $SEC 1
J 0
(-175 -1025);
DISPLAY 0.680851 (-175 -1025);
PAINT MONO (-175 -1025);
DISPLAY INVISIBLE (-175 -1025);
FORCEPROP 2 LAST CDS_SEC 1
J 0
(-175 -1025);
DISPLAY 1.021277 (-175 -1025);
DISPLAY INVISIBLE (-175 -1025);
FORCEADD OFFPAGE..2
(2050 -1025);
FORCEPROP 2 LAST $XR4 44 
J 0
(2689 -1025);
DISPLAY 0.638298 (2689 -1025);
PAINT MONO (2689 -1025);
FORCEPROP 2 LAST $XR3 13 
J 0
(2599 -1025);
DISPLAY 0.638298 (2599 -1025);
PAINT MONO (2599 -1025);
FORCEPROP 2 LAST $XR2 182 
J 0
(2479 -1025);
DISPLAY 0.638298 (2479 -1025);
PAINT MONO (2479 -1025);
FORCEPROP 2 LAST $XR1 134 
J 0
(2359 -1025);
DISPLAY 0.638298 (2359 -1025);
PAINT MONO (2359 -1025);
FORCEPROP 2 LAST $XR0 131 
J 0
(2239 -1025);
DISPLAY 0.638298 (2239 -1025);
PAINT MONO (2239 -1025);
FORCEPROP 2 LAST CDS_LIB standard
J 0
(2050 -1025);
PAINT MONO (2050 -1025);
DISPLAY INVISIBLE (2050 -1025);
FORCEPROP 1 LAST OFFPAGE TRUE
J 0
(2375 -1150);
DISPLAY 0.872340 (2375 -1150);
PAINT GREEN (2375 -1150);
DISPLAY INVISIBLE (2375 -1150);
FORCEPROP 1 LAST COMMENT_BODY TRUE
J 0
(2005 -1120);
DISPLAY 0.872340 (2005 -1120);
PAINT GREEN (2005 -1120);
DISPLAY INVISIBLE (2005 -1120);
FORCEPROP 2 LAST PATH I131
J 0
(2225 -950);
DISPLAY 1.021277 (2225 -950);
DISPLAY INVISIBLE (2225 -950);
FORCEADD Q_RES..2
(725 -1225);
FORCEPROP 1 LAST PART_NUMBER CS07502FB04
J 0
(765 -1350);
DISPLAY 0.510638 (765 -1350);
DISPLAY INVISIBLE (765 -1350);
FORCEPROP 1 LAST PACK_TYPE 0402LF
J 0
(765 -1400);
DISPLAY 0.510638 (765 -1400);
FORCEPROP 1 LAST VALUE 75
J 0
(770 -1150);
DISPLAY 0.510638 (770 -1150);
FORCEPROP 1 LAST TOLERANCE 1%
J 0
(770 -1200);
DISPLAY 0.510638 (770 -1200);
FORCEPROP 1 LAST MATERIAL CHIP
J 0
(765 -1300);
DISPLAY 0.510638 (765 -1300);
FORCEPROP 1 LAST WATTAGE 1/16W
J 0
(765 -1250);
DISPLAY 0.510638 (765 -1250);
FORCEPROP 1 LAST $LOCATION R774
J 0
(770 -1100);
DISPLAY 0.978723 (770 -1100);
FORCEPROP 1 LASTPIN (725 -1125) $PN 1
J 0
(730 -1163);
DISPLAY 0.787234 (730 -1163);
FORCEPROP 1 LASTPIN (725 -1325) $PN 2
J 0
(730 -1315);
DISPLAY 0.787234 (730 -1315);
FORCEPROP 2 LAST CDS_LIB pure_quanta
J 0
(725 -1225);
PAINT MONO (725 -1225);
DISPLAY INVISIBLE (725 -1225);
FORCEPROP 1 LAST PATH I132
J 0
(775 -1050);
DISPLAY 0.978723 (775 -1050);
PAINT WHITE (775 -1050);
DISPLAY INVISIBLE (775 -1050);
FORCEPROP 2 LAST CDS_LOCATION R774
J 0
(775 -1000);
DISPLAY 1.021277 (775 -1000);
DISPLAY INVISIBLE (775 -1000);
FORCEPROP 2 LAST $SEC 1
J 0
(775 -1000);
DISPLAY 0.680851 (775 -1000);
PAINT MONO (775 -1000);
DISPLAY INVISIBLE (775 -1000);
FORCEPROP 2 LAST CDS_SEC 1
J 0
(775 -1000);
DISPLAY 1.021277 (775 -1000);
DISPLAY INVISIBLE (775 -1000);
FORCEADD UNIVERSAL_GND..1
(725 -1475);
FORCEPROP 3 LASTPIN (725 -1425) SIG_NAME GND\g
J 0
(735 -1415);
DISPLAY 0.659574 (735 -1415);
PAINT MONO (735 -1415);
DISPLAY INVISIBLE (735 -1415);
FORCEPROP 2 LAST CDS_LIB logical_power
J 0
(725 -1475);
PAINT MONO (725 -1475);
DISPLAY INVISIBLE (725 -1475);
FORCEPROP 1 LAST HDL_POWER GND
J 1
(750 -1550);
DISPLAY 0.872340 (750 -1550);
PAINT GREEN (750 -1550);
DISPLAY INVISIBLE (750 -1550);
FORCEPROP 1 LAST PATH I133
J 0
(800 -1475);
DISPLAY 0.872340 (800 -1475);
PAINT AQUA (800 -1475);
DISPLAY INVISIBLE (800 -1475);
FORCEADD OFFPAGE..4
(2050 -875);
FORCEPROP 2 LAST $XR2 182 
J 0
(2476 -875);
DISPLAY 0.638298 (2476 -875);
PAINT MONO (2476 -875);
FORCEPROP 2 LAST $XR1 244 
J 0
(2356 -875);
DISPLAY 0.638298 (2356 -875);
PAINT MONO (2356 -875);
FORCEPROP 2 LAST $XR0 223 
J 0
(2236 -875);
DISPLAY 0.638298 (2236 -875);
PAINT MONO (2236 -875);
FORCEPROP 2 LAST CDS_LIB standard
J 0
(2050 -875);
PAINT MONO (2050 -875);
DISPLAY INVISIBLE (2050 -875);
FORCEPROP 1 LAST OFFPAGE TRUE
J 0
(2375 -1000);
DISPLAY 1.170213 (2375 -1000);
PAINT GREEN (2375 -1000);
DISPLAY INVISIBLE (2375 -1000);
FORCEPROP 1 LAST COMMENT_BODY TRUE
J 0
(2025 -975);
DISPLAY 1.170213 (2025 -975);
PAINT GREEN (2025 -975);
DISPLAY INVISIBLE (2025 -975);
FORCEPROP 2 LAST PATH I134
J 0
(2225 -800);
DISPLAY 1.021277 (2225 -800);
DISPLAY INVISIBLE (2225 -800);
FORCEADD OFFPAGE..2
R 2
(-1225 -875);
FORCEPROP 2 LAST $XR0 131 
J 0
(-1480 -875);
DISPLAY 0.638298 (-1480 -875);
PAINT MONO (-1480 -875);
FORCEPROP 2 LAST CDS_LIB standard
J 0
(-1225 -875);
PAINT MONO (-1225 -875);
DISPLAY INVISIBLE (-1225 -875);
FORCEPROP 1 LAST OFFPAGE TRUE
J 2
(-1550 -1000);
DISPLAY 0.872340 (-1550 -1000);
DISPLAY INVISIBLE (-1550 -1000);
FORCEPROP 1 LAST COMMENT_BODY TRUE
J 2
(-1180 -970);
DISPLAY 0.872340 (-1180 -970);
PAINT GREEN (-1180 -970);
DISPLAY INVISIBLE (-1180 -970);
FORCEPROP 2 LAST PATH I137
J 0
(-1175 -800);
DISPLAY 1.021277 (-1175 -800);
DISPLAY INVISIBLE (-1175 -800);
FORCEADD OFFPAGE..1
(-1225 -725);
FORCEPROP 2 LAST $XR0 131 
J 0
(-1507 -725);
DISPLAY 0.638298 (-1507 -725);
PAINT MONO (-1507 -725);
FORCEPROP 2 LAST CDS_LIB standard
J 0
(-1225 -725);
PAINT MONO (-1225 -725);
DISPLAY INVISIBLE (-1225 -725);
FORCEPROP 1 LAST OFFPAGE TRUE
J 0
(-900 -850);
DISPLAY 0.872340 (-900 -850);
PAINT GREEN (-900 -850);
DISPLAY INVISIBLE (-900 -850);
FORCEPROP 1 LAST COMMENT_BODY TRUE
J 0
(-1100 -825);
DISPLAY 0.872340 (-1100 -825);
PAINT GREEN (-1100 -825);
DISPLAY INVISIBLE (-1100 -825);
FORCEPROP 2 LAST PATH I138
J 0
(-1500 -675);
DISPLAY 1.021277 (-1500 -675);
DISPLAY INVISIBLE (-1500 -675);
FORCEADD OFFPAGE..2
R 2
(-1225 -650);
FORCEPROP 2 LAST $XR0 131 
J 0
(-1480 -650);
DISPLAY 0.638298 (-1480 -650);
PAINT MONO (-1480 -650);
FORCEPROP 2 LAST CDS_LIB standard
J 0
(-1225 -650);
PAINT MONO (-1225 -650);
DISPLAY INVISIBLE (-1225 -650);
FORCEPROP 1 LAST OFFPAGE TRUE
J 2
(-1550 -775);
DISPLAY 0.872340 (-1550 -775);
DISPLAY INVISIBLE (-1550 -775);
FORCEPROP 1 LAST COMMENT_BODY TRUE
J 2
(-1180 -745);
DISPLAY 0.872340 (-1180 -745);
PAINT GREEN (-1180 -745);
DISPLAY INVISIBLE (-1180 -745);
FORCEPROP 2 LAST PATH I139
J 0
(-1175 -575);
DISPLAY 1.021277 (-1175 -575);
DISPLAY INVISIBLE (-1175 -575);
FORCEADD UNIVERSAL_POWER..1
(1750 2725);
FORCEPROP 3 LASTPIN (1750 2675) SIG_NAME P3V3_AUX\g
J 0
(1760 2685);
DISPLAY 0.659574 (1760 2685);
PAINT MONO (1760 2685);
DISPLAY INVISIBLE (1760 2685);
FORCEPROP 1 LAST HDL_POWER P3V3_AUX
J 1
(1750 2775);
DISPLAY 0.702128 (1750 2775);
PAINT GREEN (1750 2775);
FORCEPROP 2 LAST CDS_LIB logical_power
J 0
(1750 2725);
PAINT MONO (1750 2725);
DISPLAY INVISIBLE (1750 2725);
FORCEPROP 1 LAST PATH I14
J 0
(1800 2750);
DISPLAY 0.872340 (1800 2750);
PAINT AQUA (1800 2750);
DISPLAY INVISIBLE (1800 2750);
FORCEADD Q_RES..1
(625 -725);
FORCEPROP 1 LAST PART_NUMBER CS03322FB03
J 0
(525 -625);
DISPLAY 0.510638 (525 -625);
DISPLAY INVISIBLE (525 -625);
FORCEPROP 1 LAST TOLERANCE 1%
J 0
(850 -725);
DISPLAY 0.510638 (850 -725);
FORCEPROP 1 LAST MATERIAL CHIP
J 0
(925 -725);
DISPLAY 0.510638 (925 -725);
FORCEPROP 1 LAST PACK_TYPE 0402LF
J 0
(525 -575);
DISPLAY 0.510638 (525 -575);
FORCEPROP 1 LAST WATTAGE 1/16W
J 2
(825 -575);
DISPLAY 0.510638 (825 -575);
FORCEPROP 1 LAST VALUE 33.2
J 2
(825 -725);
DISPLAY 0.510638 (825 -725);
FORCEPROP 1 LAST $LOCATION R1472
J 0
(400 -725);
DISPLAY 0.638298 (400 -725);
FORCEPROP 1 LASTPIN (525 -725) $PN 1
J 0
(537 -713);
DISPLAY 0.787234 (537 -713);
FORCEPROP 1 LASTPIN (725 -725) $PN 2
J 0
(687 -713);
DISPLAY 0.787234 (687 -713);
FORCEPROP 2 LAST CDS_LIB pure_quanta
J 0
(625 -725);
PAINT MONO (625 -725);
DISPLAY INVISIBLE (625 -725);
FORCEPROP 1 LAST PATH I144
J 0
(575 -575);
DISPLAY 0.978723 (575 -575);
PAINT WHITE (575 -575);
DISPLAY INVISIBLE (575 -575);
FORCEPROP 2 LAST CDS_LOCATION R1472
J 0
(575 -525);
DISPLAY 1.021277 (575 -525);
DISPLAY INVISIBLE (575 -525);
FORCEPROP 2 LAST $SEC 1
J 0
(575 -525);
DISPLAY 0.680851 (575 -525);
PAINT MONO (575 -525);
DISPLAY INVISIBLE (575 -525);
FORCEPROP 2 LAST CDS_SEC 1
J 0
(575 -525);
DISPLAY 1.021277 (575 -525);
DISPLAY INVISIBLE (575 -525);
FORCEADD OFFPAGE..2
R 2
(-2700 2925);
FORCEPROP 2 LAST $XR1 239 
J 0
(-3105 2925);
DISPLAY 0.638298 (-3105 2925);
PAINT MONO (-3105 2925);
FORCEPROP 2 LAST $XR0 132 
J 0
(-2985 2925);
DISPLAY 0.638298 (-2985 2925);
PAINT MONO (-2985 2925);
FORCEPROP 2 LAST CDS_LIB standard
J 0
(-2700 2925);
DISPLAY INVISIBLE (-2700 2925);
FORCEPROP 1 LAST OFFPAGE TRUE
J 2
(-3025 2800);
DISPLAY 0.872340 (-3025 2800);
DISPLAY INVISIBLE (-3025 2800);
FORCEPROP 1 LAST COMMENT_BODY TRUE
J 2
(-2655 2830);
DISPLAY 0.872340 (-2655 2830);
PAINT GREEN (-2655 2830);
DISPLAY INVISIBLE (-2655 2830);
FORCEPROP 2 LAST PATH I145
J 0
(-2975 2975);
DISPLAY 1.021277 (-2975 2975);
DISPLAY INVISIBLE (-2975 2975);
FORCEADD OFFPAGE..3
(1725 700);
FORCEPROP 2 LAST $XR0 131 
J 0
(1939 700);
DISPLAY 0.638298 (1939 700);
PAINT MONO (1939 700);
FORCEPROP 2 LAST CDS_LIB standard
J 0
(1725 700);
PAINT MONO (1725 700);
DISPLAY INVISIBLE (1725 700);
FORCEPROP 1 LAST OFFPAGE TRUE
J 0
(2050 575);
DISPLAY 0.872340 (2050 575);
DISPLAY INVISIBLE (2050 575);
FORCEPROP 1 LAST COMMENT_BODY TRUE
J 0
(1675 600);
DISPLAY 0.872340 (1675 600);
PAINT GREEN (1675 600);
DISPLAY INVISIBLE (1675 600);
FORCEPROP 2 LAST PATH I147
J 0
(2200 750);
DISPLAY 1.021277 (2200 750);
DISPLAY INVISIBLE (2200 750);
FORCEADD Q_RES..1
(625 750);
FORCEPROP 1 LAST PART_NUMBER CS03322FB03
J 0
(525 850);
DISPLAY 0.510638 (525 850);
DISPLAY INVISIBLE (525 850);
FORCEPROP 1 LAST TOLERANCE 1%
J 0
(850 750);
DISPLAY 0.510638 (850 750);
FORCEPROP 1 LAST WATTAGE 1/16W
J 2
(825 900);
DISPLAY 0.510638 (825 900);
FORCEPROP 1 LAST VALUE 33.2
J 2
(825 750);
DISPLAY 0.510638 (825 750);
FORCEPROP 1 LAST MATERIAL CHIP
J 0
(925 750);
DISPLAY 0.510638 (925 750);
FORCEPROP 1 LAST PACK_TYPE 0402LF
J 0
(525 900);
DISPLAY 0.510638 (525 900);
FORCEPROP 1 LAST $LOCATION R4502
J 0
(425 750);
DISPLAY 0.638298 (425 750);
FORCEPROP 1 LASTPIN (525 750) $PN 1
J 0
(537 762);
DISPLAY 0.787234 (537 762);
PAINT MONO (537 762);
FORCEPROP 1 LASTPIN (725 750) $PN 2
J 0
(687 762);
DISPLAY 0.787234 (687 762);
PAINT MONO (687 762);
FORCEPROP 2 LAST CDS_LIB pure_quanta
J 0
(625 750);
DISPLAY INVISIBLE (625 750);
FORCEPROP 1 LAST PATH I148
J 0
(575 900);
DISPLAY 0.978723 (575 900);
PAINT WHITE (575 900);
DISPLAY INVISIBLE (575 900);
FORCEPROP 0 LAST CDS_LOCATION R4502
J 0
(825 925);
DISPLAY 1.021277 (825 925);
DISPLAY INVISIBLE (825 925);
FORCEPROP 0 LAST $SEC 1
J 0
(825 925);
DISPLAY 0.680851 (825 925);
PAINT MONO (825 925);
DISPLAY INVISIBLE (825 925);
FORCEPROP 0 LAST CDS_SEC 1
J 0
(825 925);
DISPLAY 1.021277 (825 925);
DISPLAY INVISIBLE (825 925);
FORCEADD Q_RES..2
(1750 2525);
FORCEPROP 1 LAST PART_NUMBER CS21002FB06
J 0
(1790 2400);
DISPLAY 0.404255 (1790 2400);
DISPLAY INVISIBLE (1790 2400);
FORCEPROP 1 LAST WATTAGE 1/16W
J 0
(1790 2500);
DISPLAY 0.510638 (1790 2500);
FORCEPROP 1 LAST TOLERANCE 1%
J 0
(1795 2550);
DISPLAY 0.510638 (1795 2550);
FORCEPROP 1 LAST VALUE 1K
J 0
(1795 2600);
DISPLAY 0.510638 (1795 2600);
FORCEPROP 1 LAST MATERIAL CHIP
J 0
(1790 2450);
DISPLAY 0.510638 (1790 2450);
FORCEPROP 1 LAST PACK_TYPE 0402LF
J 0
(1790 2350);
DISPLAY 0.510638 (1790 2350);
FORCEPROP 1 LAST $LOCATION R778
J 0
(1795 2650);
DISPLAY 0.978723 (1795 2650);
FORCEPROP 1 LASTPIN (1750 2625) $PN 1
J 0
(1755 2587);
DISPLAY 0.787234 (1755 2587);
FORCEPROP 1 LASTPIN (1750 2425) $PN 2
J 0
(1755 2435);
DISPLAY 0.787234 (1755 2435);
FORCEPROP 2 LAST CDS_LIB pure_quanta
J 0
(1750 2525);
PAINT MONO (1750 2525);
DISPLAY INVISIBLE (1750 2525);
FORCEPROP 1 LAST PATH I15
J 0
(1800 2700);
DISPLAY 0.978723 (1800 2700);
PAINT WHITE (1800 2700);
DISPLAY INVISIBLE (1800 2700);
FORCEPROP 2 LAST CDS_LOCATION R778
J 0
(1800 2750);
DISPLAY 1.021277 (1800 2750);
DISPLAY INVISIBLE (1800 2750);
FORCEPROP 2 LAST $SEC 1
J 0
(1800 2750);
DISPLAY 0.680851 (1800 2750);
PAINT MONO (1800 2750);
DISPLAY INVISIBLE (1800 2750);
FORCEPROP 2 LAST CDS_SEC 1
J 0
(1800 2750);
DISPLAY 1.021277 (1800 2750);
DISPLAY INVISIBLE (1800 2750);
FORCEADD OFFPAGE..3
R 2
(-425 700);
FORCEPROP 2 LAST $XR1 241 
J 0
(-855 700);
DISPLAY 0.638298 (-855 700);
PAINT MONO (-855 700);
FORCEPROP 2 LAST $XR0 213 
J 0
(-735 700);
DISPLAY 0.638298 (-735 700);
PAINT MONO (-735 700);
FORCEPROP 2 LAST CDS_LIB standard
J 2
(-425 700);
DISPLAY INVISIBLE (-425 700);
FORCEPROP 1 LAST OFFPAGE TRUE
J 2
(-750 575);
DISPLAY 0.872340 (-750 575);
DISPLAY INVISIBLE (-750 575);
FORCEPROP 1 LAST COMMENT_BODY TRUE
J 2
(-375 600);
DISPLAY 0.872340 (-375 600);
PAINT GREEN (-375 600);
DISPLAY INVISIBLE (-375 600);
FORCEPROP 2 LAST PATH I150
J 2
(-625 775);
DISPLAY 1.021277 (-625 775);
DISPLAY INVISIBLE (-625 775);
FORCEADD OFFPAGE..2
(1725 750);
FORCEPROP 2 LAST $XR0 131 
J 0
(1914 750);
DISPLAY 0.638298 (1914 750);
PAINT MONO (1914 750);
FORCEPROP 2 LAST CDS_LIB standard
J 0
(1725 750);
DISPLAY INVISIBLE (1725 750);
FORCEPROP 1 LAST OFFPAGE TRUE
J 0
(2050 625);
DISPLAY 0.872340 (2050 625);
PAINT GREEN (2050 625);
DISPLAY INVISIBLE (2050 625);
FORCEPROP 1 LAST COMMENT_BODY TRUE
J 0
(1680 655);
DISPLAY 0.872340 (1680 655);
PAINT GREEN (1680 655);
DISPLAY INVISIBLE (1680 655);
FORCEPROP 2 LAST PATH I151
J 0
(1900 825);
DISPLAY 1.021277 (1900 825);
DISPLAY INVISIBLE (1900 825);
FORCEADD OFFPAGE..2
R 2
(-425 750);
FORCEPROP 2 LAST $XR1 213 
J 0
(-800 750);
DISPLAY 0.638298 (-800 750);
PAINT MONO (-800 750);
FORCEPROP 2 LAST $XR0 241 
J 0
(-680 750);
DISPLAY 0.638298 (-680 750);
PAINT MONO (-680 750);
FORCEPROP 2 LAST CDS_LIB standard
J 2
(-425 750);
DISPLAY INVISIBLE (-425 750);
FORCEPROP 1 LAST OFFPAGE TRUE
J 2
(-750 625);
DISPLAY 0.872340 (-750 625);
PAINT GREEN (-750 625);
DISPLAY INVISIBLE (-750 625);
FORCEPROP 1 LAST COMMENT_BODY TRUE
J 2
(-380 655);
DISPLAY 0.872340 (-380 655);
PAINT GREEN (-380 655);
DISPLAY INVISIBLE (-380 655);
FORCEPROP 2 LAST PATH I152
J 2
(-600 825);
DISPLAY 1.021277 (-600 825);
DISPLAY INVISIBLE (-600 825);
FORCEADD Q_RES..1
(625 700);
FORCEPROP 1 LAST PART_NUMBER CS00002JB13
J 0
(750 725);
DISPLAY 0.319149 (750 725);
DISPLAY INVISIBLE (750 725);
FORCEPROP 1 LAST MATERIAL CHIP
J 0
(800 700);
DISPLAY 0.319149 (800 700);
FORCEPROP 1 LAST VALUE 0
J 2
(775 700);
DISPLAY 0.510638 (775 700);
FORCEPROP 1 LAST $LOCATION R4503
J 0
(425 700);
DISPLAY 0.638298 (425 700);
FORCEPROP 1 LASTPIN (525 700) $PN 1
J 0
(537 712);
DISPLAY 0.787234 (537 712);
PAINT MONO (537 712);
FORCEPROP 1 LASTPIN (725 700) $PN 2
J 0
(687 712);
DISPLAY 0.787234 (687 712);
PAINT MONO (687 712);
FORCEPROP 2 LAST CDS_LIB pure_quanta
J 0
(625 700);
DISPLAY INVISIBLE (625 700);
FORCEPROP 1 LAST PACK_TYPE 0402LF
J 0
(900 700);
DISPLAY 0.510638 (900 700);
DISPLAY INVISIBLE (900 700);
FORCEPROP 1 LAST TOLERANCE 5%
J 0
(800 700);
DISPLAY 0.510638 (800 700);
DISPLAY INVISIBLE (800 700);
FORCEPROP 1 LAST WATTAGE 1/16W
J 2
(925 750);
DISPLAY 0.319149 (925 750);
DISPLAY INVISIBLE (925 750);
FORCEPROP 1 LAST PATH I153
J 0
(575 850);
DISPLAY 0.978723 (575 850);
PAINT WHITE (575 850);
DISPLAY INVISIBLE (575 850);
FORCEPROP 0 LAST CDS_LOCATION R4503
J 0
(425 750);
DISPLAY 1.021277 (425 750);
DISPLAY INVISIBLE (425 750);
FORCEPROP 0 LAST $SEC 1
J 0
(425 750);
DISPLAY 0.680851 (425 750);
PAINT MONO (425 750);
DISPLAY INVISIBLE (425 750);
FORCEPROP 0 LAST CDS_SEC 1
J 0
(425 750);
DISPLAY 1.021277 (425 750);
DISPLAY INVISIBLE (425 750);
FORCEADD OFFPAGE..2
(1575 2225);
FORCEPROP 2 LAST $XR0 131 
J 0
(1764 2225);
DISPLAY 0.638298 (1764 2225);
PAINT MONO (1764 2225);
FORCEPROP 2 LAST CDS_LIB standard
J 0
(1575 2225);
DISPLAY INVISIBLE (1575 2225);
FORCEPROP 1 LAST OFFPAGE TRUE
J 0
(1900 2100);
DISPLAY 0.872340 (1900 2100);
PAINT GREEN (1900 2100);
DISPLAY INVISIBLE (1900 2100);
FORCEPROP 1 LAST COMMENT_BODY TRUE
J 0
(1530 2130);
DISPLAY 0.872340 (1530 2130);
PAINT GREEN (1530 2130);
DISPLAY INVISIBLE (1530 2130);
FORCEPROP 2 LAST PATH I16
J 0
(1750 2300);
DISPLAY 1.021277 (1750 2300);
DISPLAY INVISIBLE (1750 2300);
FORCEADD UNIVERSAL_POWER..1
(1825 1775);
FORCEPROP 3 LASTPIN (1825 1725) SIG_NAME P3V3_AUX\g
J 0
(1835 1735);
DISPLAY 0.659574 (1835 1735);
PAINT MONO (1835 1735);
DISPLAY INVISIBLE (1835 1735);
FORCEPROP 1 LAST HDL_POWER P3V3_AUX
J 1
(1825 1825);
DISPLAY 0.872340 (1825 1825);
PAINT GREEN (1825 1825);
FORCEPROP 2 LAST CDS_LIB logical_power
J 0
(1825 1775);
PAINT MONO (1825 1775);
DISPLAY INVISIBLE (1825 1775);
FORCEPROP 1 LAST PATH I20
J 0
(1875 1800);
DISPLAY 0.872340 (1875 1800);
PAINT AQUA (1875 1800);
DISPLAY INVISIBLE (1875 1800);
FORCEADD OFFPAGE..2
(2725 3175);
FORCEPROP 2 LAST $XR1 132 
J 0
(3034 3175);
DISPLAY 0.638298 (3034 3175);
PAINT MONO (3034 3175);
FORCEPROP 2 LAST $XR0 239 
J 0
(2914 3175);
DISPLAY 0.638298 (2914 3175);
PAINT MONO (2914 3175);
FORCEPROP 2 LAST CDS_LIB standard
J 0
(2725 3175);
DISPLAY INVISIBLE (2725 3175);
FORCEPROP 1 LAST OFFPAGE TRUE
J 0
(3050 3050);
DISPLAY 0.872340 (3050 3050);
PAINT GREEN (3050 3050);
DISPLAY INVISIBLE (3050 3050);
FORCEPROP 1 LAST COMMENT_BODY TRUE
J 0
(2680 3080);
DISPLAY 0.872340 (2680 3080);
PAINT GREEN (2680 3080);
DISPLAY INVISIBLE (2680 3080);
FORCEPROP 2 LAST PATH I4
J 0
(3225 3225);
DISPLAY 1.021277 (3225 3225);
DISPLAY INVISIBLE (3225 3225);
FORCEADD SCONN60_ASP21410801..1
(375 2425);
FORCEPROP 1 LAST PART_NUMBER DFHS60FS108
J 0
(279 3413);
DISPLAY 0.723404 (279 3413);
PAINT GREEN (279 3413);
DISPLAY INVISIBLE (279 3413);
FORCEPROP 2 LAST VALUE SCONN60_ASP-214108-01
J 0
(125 3475);
DISPLAY 0.404255 (125 3475);
FORCEPROP 2 LAST PART_TYPE SMLF
J 0
(125 3525);
DISPLAY 0.404255 (125 3525);
FORCEPROP 1 LAST MATERIAL IO
J 0
(279 3286);
DISPLAY 0.723404 (279 3286);
PAINT GREEN (279 3286);
FORCEPROP 1 LAST $LOCATION J42
J 0
(279 3560);
DISPLAY 0.723404 (279 3560);
PAINT GREEN (279 3560);
FORCEPROP 0 LASTPIN (125 3175) $PN 1
J 2
(115 3185);
DISPLAY 0.680851 (115 3185);
PAINT MONO (115 3185);
FORCEPROP 0 LASTPIN (625 3175) $PN 2
J 0
(635 3185);
DISPLAY 0.680851 (635 3185);
PAINT MONO (635 3185);
FORCEPROP 0 LASTPIN (125 3125) $PN 3
J 2
(115 3135);
DISPLAY 0.680851 (115 3135);
PAINT MONO (115 3135);
FORCEPROP 0 LASTPIN (625 3125) $PN 4
J 0
(635 3135);
DISPLAY 0.680851 (635 3135);
PAINT MONO (635 3135);
FORCEPROP 0 LASTPIN (125 3075) $PN 5
J 2
(115 3085);
DISPLAY 0.680851 (115 3085);
PAINT MONO (115 3085);
FORCEPROP 0 LASTPIN (625 3075) $PN 6
J 0
(635 3085);
DISPLAY 0.680851 (635 3085);
PAINT MONO (635 3085);
FORCEPROP 0 LASTPIN (125 3025) $PN 7
J 2
(115 3035);
DISPLAY 0.680851 (115 3035);
PAINT MONO (115 3035);
FORCEPROP 0 LASTPIN (625 3025) $PN 8
J 0
(635 3035);
DISPLAY 0.680851 (635 3035);
PAINT MONO (635 3035);
FORCEPROP 0 LASTPIN (125 2975) $PN 9
J 2
(115 2985);
DISPLAY 0.680851 (115 2985);
PAINT MONO (115 2985);
FORCEPROP 0 LASTPIN (625 2975) $PN 10
J 0
(635 2985);
DISPLAY 0.680851 (635 2985);
PAINT MONO (635 2985);
FORCEPROP 0 LASTPIN (125 2925) $PN 11
J 2
(115 2935);
DISPLAY 0.680851 (115 2935);
PAINT MONO (115 2935);
FORCEPROP 0 LASTPIN (625 2925) $PN 12
J 0
(635 2935);
DISPLAY 0.680851 (635 2935);
PAINT MONO (635 2935);
FORCEPROP 0 LASTPIN (125 2875) $PN 13
J 2
(115 2885);
DISPLAY 0.680851 (115 2885);
PAINT MONO (115 2885);
FORCEPROP 0 LASTPIN (625 2875) $PN 14
J 0
(635 2885);
DISPLAY 0.680851 (635 2885);
PAINT MONO (635 2885);
FORCEPROP 0 LASTPIN (125 2825) $PN 15
J 2
(115 2835);
DISPLAY 0.680851 (115 2835);
PAINT MONO (115 2835);
FORCEPROP 0 LASTPIN (625 2825) $PN 16
J 0
(635 2835);
DISPLAY 0.680851 (635 2835);
PAINT MONO (635 2835);
FORCEPROP 0 LASTPIN (125 2775) $PN 17
J 2
(115 2785);
DISPLAY 0.680851 (115 2785);
PAINT MONO (115 2785);
FORCEPROP 0 LASTPIN (625 2775) $PN 18
J 0
(635 2785);
DISPLAY 0.680851 (635 2785);
PAINT MONO (635 2785);
FORCEPROP 0 LASTPIN (125 2725) $PN 19
J 2
(115 2735);
DISPLAY 0.680851 (115 2735);
PAINT MONO (115 2735);
FORCEPROP 0 LASTPIN (625 2725) $PN 20
J 0
(635 2735);
DISPLAY 0.680851 (635 2735);
PAINT MONO (635 2735);
FORCEPROP 0 LASTPIN (125 2675) $PN 21
J 2
(115 2685);
DISPLAY 0.680851 (115 2685);
PAINT MONO (115 2685);
FORCEPROP 0 LASTPIN (625 2675) $PN 22
J 0
(635 2685);
DISPLAY 0.680851 (635 2685);
PAINT MONO (635 2685);
FORCEPROP 0 LASTPIN (125 2625) $PN 23
J 2
(115 2635);
DISPLAY 0.680851 (115 2635);
PAINT MONO (115 2635);
FORCEPROP 0 LASTPIN (625 2625) $PN 24
J 0
(635 2635);
DISPLAY 0.680851 (635 2635);
PAINT MONO (635 2635);
FORCEPROP 0 LASTPIN (125 2575) $PN 25
J 2
(115 2585);
DISPLAY 0.680851 (115 2585);
PAINT MONO (115 2585);
FORCEPROP 0 LASTPIN (625 2575) $PN 26
J 0
(635 2585);
DISPLAY 0.680851 (635 2585);
PAINT MONO (635 2585);
FORCEPROP 0 LASTPIN (125 2525) $PN 27
J 2
(115 2535);
DISPLAY 0.680851 (115 2535);
PAINT MONO (115 2535);
FORCEPROP 0 LASTPIN (625 2525) $PN 28
J 0
(635 2535);
DISPLAY 0.680851 (635 2535);
PAINT MONO (635 2535);
FORCEPROP 0 LASTPIN (125 2475) $PN 29
J 2
(115 2485);
DISPLAY 0.680851 (115 2485);
PAINT MONO (115 2485);
FORCEPROP 0 LASTPIN (625 2475) $PN 30
J 0
(635 2485);
DISPLAY 0.680851 (635 2485);
PAINT MONO (635 2485);
FORCEPROP 0 LASTPIN (125 2425) $PN 31
J 2
(115 2435);
DISPLAY 0.680851 (115 2435);
PAINT MONO (115 2435);
FORCEPROP 0 LASTPIN (625 2425) $PN 32
J 0
(635 2435);
DISPLAY 0.680851 (635 2435);
PAINT MONO (635 2435);
FORCEPROP 0 LASTPIN (125 2375) $PN 33
J 2
(115 2385);
DISPLAY 0.680851 (115 2385);
PAINT MONO (115 2385);
FORCEPROP 0 LASTPIN (625 2375) $PN 34
J 0
(635 2385);
DISPLAY 0.680851 (635 2385);
PAINT MONO (635 2385);
FORCEPROP 0 LASTPIN (125 2325) $PN 35
J 2
(115 2335);
DISPLAY 0.680851 (115 2335);
PAINT MONO (115 2335);
FORCEPROP 0 LASTPIN (625 2325) $PN 36
J 0
(635 2335);
DISPLAY 0.680851 (635 2335);
PAINT MONO (635 2335);
FORCEPROP 0 LASTPIN (125 2275) $PN 37
J 2
(115 2285);
DISPLAY 0.680851 (115 2285);
PAINT MONO (115 2285);
FORCEPROP 0 LASTPIN (625 2275) $PN 38
J 0
(635 2285);
DISPLAY 0.680851 (635 2285);
PAINT MONO (635 2285);
FORCEPROP 0 LASTPIN (125 2225) $PN 39
J 2
(115 2235);
DISPLAY 0.680851 (115 2235);
PAINT MONO (115 2235);
FORCEPROP 0 LASTPIN (625 2225) $PN 40
J 0
(635 2235);
DISPLAY 0.680851 (635 2235);
PAINT MONO (635 2235);
FORCEPROP 0 LASTPIN (125 2175) $PN 41
J 2
(115 2185);
DISPLAY 0.680851 (115 2185);
PAINT MONO (115 2185);
FORCEPROP 0 LASTPIN (625 2175) $PN 42
J 0
(635 2185);
DISPLAY 0.680851 (635 2185);
PAINT MONO (635 2185);
FORCEPROP 0 LASTPIN (125 2125) $PN 43
J 2
(115 2135);
DISPLAY 0.680851 (115 2135);
PAINT MONO (115 2135);
FORCEPROP 0 LASTPIN (625 2125) $PN 44
J 0
(635 2135);
DISPLAY 0.680851 (635 2135);
PAINT MONO (635 2135);
FORCEPROP 0 LASTPIN (125 2075) $PN 45
J 2
(115 2085);
DISPLAY 0.680851 (115 2085);
PAINT MONO (115 2085);
FORCEPROP 0 LASTPIN (625 2075) $PN 46
J 0
(635 2085);
DISPLAY 0.680851 (635 2085);
PAINT MONO (635 2085);
FORCEPROP 0 LASTPIN (125 2025) $PN 47
J 2
(115 2035);
DISPLAY 0.680851 (115 2035);
PAINT MONO (115 2035);
FORCEPROP 0 LASTPIN (625 2025) $PN 48
J 0
(635 2035);
DISPLAY 0.680851 (635 2035);
PAINT MONO (635 2035);
FORCEPROP 0 LASTPIN (125 1975) $PN 49
J 2
(115 1985);
DISPLAY 0.680851 (115 1985);
PAINT MONO (115 1985);
FORCEPROP 0 LASTPIN (625 1975) $PN 50
J 0
(635 1985);
DISPLAY 0.680851 (635 1985);
PAINT MONO (635 1985);
FORCEPROP 0 LASTPIN (125 1925) $PN 51
J 2
(115 1935);
DISPLAY 0.680851 (115 1935);
PAINT MONO (115 1935);
FORCEPROP 0 LASTPIN (625 1925) $PN 52
J 0
(635 1935);
DISPLAY 0.680851 (635 1935);
PAINT MONO (635 1935);
FORCEPROP 0 LASTPIN (125 1875) $PN 53
J 2
(115 1885);
DISPLAY 0.680851 (115 1885);
PAINT MONO (115 1885);
FORCEPROP 0 LASTPIN (625 1875) $PN 54
J 0
(635 1885);
DISPLAY 0.680851 (635 1885);
PAINT MONO (635 1885);
FORCEPROP 0 LASTPIN (125 1825) $PN 55
J 2
(115 1835);
DISPLAY 0.680851 (115 1835);
PAINT MONO (115 1835);
FORCEPROP 0 LASTPIN (625 1825) $PN 56
J 0
(635 1835);
DISPLAY 0.680851 (635 1835);
PAINT MONO (635 1835);
FORCEPROP 0 LASTPIN (125 1775) $PN 57
J 2
(115 1785);
DISPLAY 0.680851 (115 1785);
PAINT MONO (115 1785);
FORCEPROP 0 LASTPIN (625 1775) $PN 58
J 0
(635 1785);
DISPLAY 0.680851 (635 1785);
PAINT MONO (635 1785);
FORCEPROP 0 LASTPIN (125 1725) $PN 59
J 2
(115 1735);
DISPLAY 0.680851 (115 1735);
PAINT MONO (115 1735);
FORCEPROP 0 LASTPIN (625 1725) $PN 60
J 0
(635 1735);
DISPLAY 0.680851 (635 1735);
PAINT MONO (635 1735);
FORCEPROP 0 LASTPIN (125 1675) $PN G1
J 2
(115 1685);
DISPLAY 0.680851 (115 1685);
PAINT MONO (115 1685);
FORCEPROP 0 LASTPIN (625 1675) $PN G2
J 0
(635 1685);
DISPLAY 0.680851 (635 1685);
PAINT MONO (635 1685);
FORCEPROP 0 LASTPIN (125 1625) $PN G3
J 2
(115 1635);
DISPLAY 0.680851 (115 1635);
PAINT MONO (115 1635);
FORCEPROP 0 LASTPIN (625 1625) $PN G4
J 0
(635 1635);
DISPLAY 0.680851 (635 1635);
PAINT MONO (635 1635);
FORCEPROP 2 LAST CDS_LIB pure_quanta
J 0
(375 2425);
DISPLAY INVISIBLE (375 2425);
FORCEPROP 1 LAST NEEDS_NO_SIZE TRUE
J 0
(375 2425);
DISPLAY 0.723404 (375 2425);
PAINT GREEN (375 2425);
DISPLAY INVISIBLE (375 2425);
FORCEPROP 1 LAST CDS_LMAN_SYM_OUTLINE -100,850,100,-850
J 0
(375 2425);
DISPLAY 0.468085 (375 2425);
PAINT GREEN (375 2425);
DISPLAY INVISIBLE (375 2425);
FORCEPROP 1 LAST PATH I44
J 0
(375 2425);
DISPLAY 0.723404 (375 2425);
PAINT GREEN (375 2425);
DISPLAY INVISIBLE (375 2425);
FORCEPROP 2 LAST CDS_LOCATION J42
J 0
(125 3550);
DISPLAY 1.021277 (125 3550);
DISPLAY INVISIBLE (125 3550);
FORCEPROP 0 LAST $SEC 1
J 0
(300 3600);
DISPLAY 0.680851 (300 3600);
PAINT MONO (300 3600);
DISPLAY INVISIBLE (300 3600);
FORCEPROP 2 LAST CDS_SEC 1
J 0
(125 3550);
DISPLAY 1.021277 (125 3550);
DISPLAY INVISIBLE (125 3550);
FORCEADD OFFPAGE..1
(-850 2875);
FORCEPROP 2 LAST $XR0 183 
J 0
(-1102 2875);
DISPLAY 0.638298 (-1102 2875);
PAINT MONO (-1102 2875);
FORCEPROP 2 LAST CDS_LIB standard
J 0
(-850 2875);
PAINT MONO (-850 2875);
DISPLAY INVISIBLE (-850 2875);
FORCEPROP 1 LAST OFFPAGE TRUE
J 0
(-525 2750);
DISPLAY 0.872340 (-525 2750);
PAINT GREEN (-525 2750);
DISPLAY INVISIBLE (-525 2750);
FORCEPROP 1 LAST COMMENT_BODY TRUE
J 0
(-725 2775);
DISPLAY 0.872340 (-725 2775);
PAINT GREEN (-725 2775);
DISPLAY INVISIBLE (-725 2775);
FORCEPROP 2 LAST PATH I45
J 0
(-1125 2925);
DISPLAY 1.021277 (-1125 2925);
DISPLAY INVISIBLE (-1125 2925);
FORCEADD OFFPAGE..1
(-850 2725);
FORCEPROP 2 LAST $XR0 183 
J 0
(-1102 2725);
DISPLAY 0.638298 (-1102 2725);
PAINT MONO (-1102 2725);
FORCEPROP 2 LAST CDS_LIB standard
J 0
(-850 2725);
PAINT MONO (-850 2725);
DISPLAY INVISIBLE (-850 2725);
FORCEPROP 1 LAST OFFPAGE TRUE
J 0
(-525 2600);
DISPLAY 0.872340 (-525 2600);
PAINT GREEN (-525 2600);
DISPLAY INVISIBLE (-525 2600);
FORCEPROP 1 LAST COMMENT_BODY TRUE
J 0
(-725 2625);
DISPLAY 0.872340 (-725 2625);
PAINT GREEN (-725 2625);
DISPLAY INVISIBLE (-725 2625);
FORCEPROP 2 LAST PATH I47
J 0
(-1125 2775);
DISPLAY 1.021277 (-1125 2775);
DISPLAY INVISIBLE (-1125 2775);
FORCEADD OFFPAGE..1
(-850 2675);
FORCEPROP 2 LAST $XR0 183 
J 0
(-1102 2675);
DISPLAY 0.638298 (-1102 2675);
PAINT MONO (-1102 2675);
FORCEPROP 2 LAST CDS_LIB standard
J 0
(-850 2675);
PAINT MONO (-850 2675);
DISPLAY INVISIBLE (-850 2675);
FORCEPROP 1 LAST OFFPAGE TRUE
J 0
(-525 2550);
DISPLAY 0.872340 (-525 2550);
PAINT GREEN (-525 2550);
DISPLAY INVISIBLE (-525 2550);
FORCEPROP 1 LAST COMMENT_BODY TRUE
J 0
(-725 2575);
DISPLAY 0.872340 (-725 2575);
PAINT GREEN (-725 2575);
DISPLAY INVISIBLE (-725 2575);
FORCEPROP 2 LAST PATH I49
J 0
(-1125 2725);
DISPLAY 1.021277 (-1125 2725);
DISPLAY INVISIBLE (-1125 2725);
FORCEADD Q_RES..1
(1625 3175);
FORCEPROP 1 LAST PART_NUMBER CS01002FB07
J 0
(1775 3200);
DISPLAY 0.319149 (1775 3200);
DISPLAY INVISIBLE (1775 3200);
FORCEPROP 1 LAST PACK_TYPE 0402LF
J 0
(1900 3175);
DISPLAY 0.510638 (1900 3175);
FORCEPROP 1 LAST VALUE 10
J 2
(1800 3175);
DISPLAY 0.510638 (1800 3175);
FORCEPROP 1 LAST MATERIAL CHIP
J 0
(1775 3225);
DISPLAY 0.319149 (1775 3225);
FORCEPROP 1 LAST WATTAGE 1/16W
J 2
(1950 3225);
DISPLAY 0.319149 (1950 3225);
FORCEPROP 1 LAST TOLERANCE 1%
J 0
(1825 3175);
DISPLAY 0.510638 (1825 3175);
FORCEPROP 1 LAST $LOCATION R775
J 0
(1425 3175);
DISPLAY 0.638298 (1425 3175);
FORCEPROP 1 LASTPIN (1525 3175) $PN 1
J 0
(1537 3187);
DISPLAY 0.787234 (1537 3187);
FORCEPROP 1 LASTPIN (1725 3175) $PN 2
J 0
(1687 3187);
DISPLAY 0.787234 (1687 3187);
FORCEPROP 2 LAST CDS_LIB pure_quanta
J 0
(1625 3175);
PAINT MONO (1625 3175);
DISPLAY INVISIBLE (1625 3175);
FORCEPROP 1 LAST PATH I5
J 0
(1575 3325);
DISPLAY 0.978723 (1575 3325);
PAINT WHITE (1575 3325);
DISPLAY INVISIBLE (1575 3325);
FORCEPROP 2 LAST CDS_LOCATION R775
J 0
(1575 3375);
DISPLAY 1.021277 (1575 3375);
DISPLAY INVISIBLE (1575 3375);
FORCEPROP 2 LAST $SEC 1
J 0
(1575 3375);
DISPLAY 0.680851 (1575 3375);
PAINT MONO (1575 3375);
DISPLAY INVISIBLE (1575 3375);
FORCEPROP 2 LAST CDS_SEC 1
J 0
(1575 3375);
DISPLAY 1.021277 (1575 3375);
DISPLAY INVISIBLE (1575 3375);
FORCEADD OFFPAGE..1
(-850 2625);
FORCEPROP 2 LAST $XR0 183 
J 0
(-1102 2625);
DISPLAY 0.638298 (-1102 2625);
PAINT MONO (-1102 2625);
FORCEPROP 2 LAST CDS_LIB standard
J 0
(-850 2625);
PAINT MONO (-850 2625);
DISPLAY INVISIBLE (-850 2625);
FORCEPROP 1 LAST OFFPAGE TRUE
J 0
(-525 2500);
DISPLAY 0.872340 (-525 2500);
PAINT GREEN (-525 2500);
DISPLAY INVISIBLE (-525 2500);
FORCEPROP 1 LAST COMMENT_BODY TRUE
J 0
(-725 2525);
DISPLAY 0.872340 (-725 2525);
PAINT GREEN (-725 2525);
DISPLAY INVISIBLE (-725 2525);
FORCEPROP 2 LAST PATH I50
J 0
(-1125 2675);
DISPLAY 1.021277 (-1125 2675);
DISPLAY INVISIBLE (-1125 2675);
FORCEADD OFFPAGE..1
(-850 2575);
FORCEPROP 2 LAST $XR0 183 
J 0
(-1102 2575);
DISPLAY 0.638298 (-1102 2575);
PAINT MONO (-1102 2575);
FORCEPROP 2 LAST CDS_LIB standard
J 0
(-850 2575);
PAINT MONO (-850 2575);
DISPLAY INVISIBLE (-850 2575);
FORCEPROP 1 LAST OFFPAGE TRUE
J 0
(-525 2450);
DISPLAY 0.872340 (-525 2450);
PAINT GREEN (-525 2450);
DISPLAY INVISIBLE (-525 2450);
FORCEPROP 1 LAST COMMENT_BODY TRUE
J 0
(-725 2475);
DISPLAY 0.872340 (-725 2475);
PAINT GREEN (-725 2475);
DISPLAY INVISIBLE (-725 2475);
FORCEPROP 2 LAST PATH I51
J 0
(-1125 2625);
DISPLAY 1.021277 (-1125 2625);
DISPLAY INVISIBLE (-1125 2625);
FORCEADD OFFPAGE..1
(-850 2475);
FORCEPROP 2 LAST $XR0 183 
J 0
(-1102 2475);
DISPLAY 0.638298 (-1102 2475);
PAINT MONO (-1102 2475);
FORCEPROP 2 LAST CDS_LIB standard
J 0
(-850 2475);
PAINT MONO (-850 2475);
DISPLAY INVISIBLE (-850 2475);
FORCEPROP 1 LAST OFFPAGE TRUE
J 0
(-525 2350);
DISPLAY 0.872340 (-525 2350);
PAINT GREEN (-525 2350);
DISPLAY INVISIBLE (-525 2350);
FORCEPROP 1 LAST COMMENT_BODY TRUE
J 0
(-725 2375);
DISPLAY 0.872340 (-725 2375);
PAINT GREEN (-725 2375);
DISPLAY INVISIBLE (-725 2375);
FORCEPROP 2 LAST PATH I52
J 0
(-1125 2525);
DISPLAY 1.021277 (-1125 2525);
DISPLAY INVISIBLE (-1125 2525);
FORCEADD OFFPAGE..1
(-850 2525);
FORCEPROP 2 LAST $XR0 183 
J 0
(-1102 2525);
DISPLAY 0.638298 (-1102 2525);
PAINT MONO (-1102 2525);
FORCEPROP 2 LAST CDS_LIB standard
J 0
(-850 2525);
PAINT MONO (-850 2525);
DISPLAY INVISIBLE (-850 2525);
FORCEPROP 1 LAST OFFPAGE TRUE
J 0
(-525 2400);
DISPLAY 0.872340 (-525 2400);
PAINT GREEN (-525 2400);
DISPLAY INVISIBLE (-525 2400);
FORCEPROP 1 LAST COMMENT_BODY TRUE
J 0
(-725 2425);
DISPLAY 0.872340 (-725 2425);
PAINT GREEN (-725 2425);
DISPLAY INVISIBLE (-725 2425);
FORCEPROP 2 LAST PATH I53
J 0
(-1125 2575);
DISPLAY 1.021277 (-1125 2575);
DISPLAY INVISIBLE (-1125 2575);
FORCEADD OFFPAGE..1
(-850 2425);
FORCEPROP 2 LAST $XR2 202 
J 0
(-1342 2425);
DISPLAY 0.638298 (-1342 2425);
PAINT MONO (-1342 2425);
FORCEPROP 2 LAST $XR1 201 
J 0
(-1222 2425);
DISPLAY 0.638298 (-1222 2425);
PAINT MONO (-1222 2425);
FORCEPROP 2 LAST $XR0 183 
J 0
(-1102 2425);
DISPLAY 0.638298 (-1102 2425);
PAINT MONO (-1102 2425);
FORCEPROP 2 LAST CDS_LIB standard
J 0
(-850 2425);
PAINT MONO (-850 2425);
DISPLAY INVISIBLE (-850 2425);
FORCEPROP 1 LAST OFFPAGE TRUE
J 0
(-525 2300);
DISPLAY 0.872340 (-525 2300);
PAINT GREEN (-525 2300);
DISPLAY INVISIBLE (-525 2300);
FORCEPROP 1 LAST COMMENT_BODY TRUE
J 0
(-725 2325);
DISPLAY 0.872340 (-725 2325);
PAINT GREEN (-725 2325);
DISPLAY INVISIBLE (-725 2325);
FORCEPROP 2 LAST PATH I54
J 0
(-1125 2475);
DISPLAY 1.021277 (-1125 2475);
DISPLAY INVISIBLE (-1125 2475);
FORCEADD OFFPAGE..1
(-850 2375);
FORCEPROP 2 LAST $XR0 183 
J 0
(-1102 2375);
DISPLAY 0.638298 (-1102 2375);
PAINT MONO (-1102 2375);
FORCEPROP 2 LAST CDS_LIB standard
J 0
(-850 2375);
PAINT MONO (-850 2375);
DISPLAY INVISIBLE (-850 2375);
FORCEPROP 1 LAST OFFPAGE TRUE
J 0
(-525 2250);
DISPLAY 0.872340 (-525 2250);
PAINT GREEN (-525 2250);
DISPLAY INVISIBLE (-525 2250);
FORCEPROP 1 LAST COMMENT_BODY TRUE
J 0
(-725 2275);
DISPLAY 0.872340 (-725 2275);
PAINT GREEN (-725 2275);
DISPLAY INVISIBLE (-725 2275);
FORCEPROP 2 LAST PATH I55
J 0
(-1125 2425);
DISPLAY 1.021277 (-1125 2425);
DISPLAY INVISIBLE (-1125 2425);
FORCEADD OFFPAGE..1
(-850 2325);
FORCEPROP 2 LAST $XR0 183 
J 0
(-1102 2325);
DISPLAY 0.638298 (-1102 2325);
PAINT MONO (-1102 2325);
FORCEPROP 2 LAST CDS_LIB standard
J 0
(-850 2325);
PAINT MONO (-850 2325);
DISPLAY INVISIBLE (-850 2325);
FORCEPROP 1 LAST OFFPAGE TRUE
J 0
(-525 2200);
DISPLAY 0.872340 (-525 2200);
PAINT GREEN (-525 2200);
DISPLAY INVISIBLE (-525 2200);
FORCEPROP 1 LAST COMMENT_BODY TRUE
J 0
(-725 2225);
DISPLAY 0.872340 (-725 2225);
PAINT GREEN (-725 2225);
DISPLAY INVISIBLE (-725 2225);
FORCEPROP 2 LAST PATH I56
J 0
(-1125 2375);
DISPLAY 1.021277 (-1125 2375);
DISPLAY INVISIBLE (-1125 2375);
FORCEADD OFFPAGE..1
(-850 2275);
FORCEPROP 2 LAST $XR0 183 
J 0
(-1102 2275);
DISPLAY 0.638298 (-1102 2275);
PAINT MONO (-1102 2275);
FORCEPROP 2 LAST CDS_LIB standard
J 0
(-850 2275);
PAINT MONO (-850 2275);
DISPLAY INVISIBLE (-850 2275);
FORCEPROP 1 LAST OFFPAGE TRUE
J 0
(-525 2150);
DISPLAY 0.872340 (-525 2150);
PAINT GREEN (-525 2150);
DISPLAY INVISIBLE (-525 2150);
FORCEPROP 1 LAST COMMENT_BODY TRUE
J 0
(-725 2175);
DISPLAY 0.872340 (-725 2175);
PAINT GREEN (-725 2175);
DISPLAY INVISIBLE (-725 2175);
FORCEPROP 2 LAST PATH I57
J 0
(-1125 2325);
DISPLAY 1.021277 (-1125 2325);
DISPLAY INVISIBLE (-1125 2325);
FORCEADD OFFPAGE..1
(-850 2225);
FORCEPROP 2 LAST $XR0 183 
J 0
(-1102 2225);
DISPLAY 0.638298 (-1102 2225);
PAINT MONO (-1102 2225);
FORCEPROP 2 LAST CDS_LIB standard
J 0
(-850 2225);
PAINT MONO (-850 2225);
DISPLAY INVISIBLE (-850 2225);
FORCEPROP 1 LAST OFFPAGE TRUE
J 0
(-525 2100);
DISPLAY 0.872340 (-525 2100);
PAINT GREEN (-525 2100);
DISPLAY INVISIBLE (-525 2100);
FORCEPROP 1 LAST COMMENT_BODY TRUE
J 0
(-725 2125);
DISPLAY 0.872340 (-725 2125);
PAINT GREEN (-725 2125);
DISPLAY INVISIBLE (-725 2125);
FORCEPROP 2 LAST PATH I58
J 0
(-1125 2275);
DISPLAY 1.021277 (-1125 2275);
DISPLAY INVISIBLE (-1125 2275);
FORCEADD OFFPAGE..1
(-850 2175);
FORCEPROP 2 LAST $XR0 183 
J 0
(-1102 2175);
DISPLAY 0.638298 (-1102 2175);
PAINT MONO (-1102 2175);
FORCEPROP 2 LAST CDS_LIB standard
J 0
(-850 2175);
PAINT MONO (-850 2175);
DISPLAY INVISIBLE (-850 2175);
FORCEPROP 1 LAST OFFPAGE TRUE
J 0
(-525 2050);
DISPLAY 0.872340 (-525 2050);
PAINT GREEN (-525 2050);
DISPLAY INVISIBLE (-525 2050);
FORCEPROP 1 LAST COMMENT_BODY TRUE
J 0
(-725 2075);
DISPLAY 0.872340 (-725 2075);
PAINT GREEN (-725 2075);
DISPLAY INVISIBLE (-725 2075);
FORCEPROP 2 LAST PATH I59
J 0
(-1125 2225);
DISPLAY 1.021277 (-1125 2225);
DISPLAY INVISIBLE (-1125 2225);
FORCEADD OFFPAGE..1
(-850 2125);
FORCEPROP 2 LAST $XR0 183 
J 0
(-1102 2125);
DISPLAY 0.638298 (-1102 2125);
PAINT MONO (-1102 2125);
FORCEPROP 2 LAST CDS_LIB standard
J 0
(-850 2125);
PAINT MONO (-850 2125);
DISPLAY INVISIBLE (-850 2125);
FORCEPROP 1 LAST OFFPAGE TRUE
J 0
(-525 2000);
DISPLAY 0.872340 (-525 2000);
PAINT GREEN (-525 2000);
DISPLAY INVISIBLE (-525 2000);
FORCEPROP 1 LAST COMMENT_BODY TRUE
J 0
(-725 2025);
DISPLAY 0.872340 (-725 2025);
PAINT GREEN (-725 2025);
DISPLAY INVISIBLE (-725 2025);
FORCEPROP 2 LAST PATH I60
J 0
(-1125 2175);
DISPLAY 1.021277 (-1125 2175);
DISPLAY INVISIBLE (-1125 2175);
FORCEADD UNIVERSAL_GND..1
(25 1500);
FORCEPROP 3 LASTPIN (25 1550) SIG_NAME GND\g
J 0
(35 1560);
DISPLAY 0.659574 (35 1560);
PAINT MONO (35 1560);
DISPLAY INVISIBLE (35 1560);
FORCEPROP 2 LAST CDS_LIB logical_power
J 0
(25 1500);
PAINT MONO (25 1500);
DISPLAY INVISIBLE (25 1500);
FORCEPROP 1 LAST HDL_POWER GND
J 1
(50 1425);
DISPLAY 0.872340 (50 1425);
PAINT GREEN (50 1425);
DISPLAY INVISIBLE (50 1425);
FORCEPROP 1 LAST PATH I61
J 0
(100 1500);
DISPLAY 0.872340 (100 1500);
PAINT AQUA (100 1500);
DISPLAY INVISIBLE (100 1500);
FORCEADD OFFPAGE..1
(-850 2075);
FORCEPROP 2 LAST $XR0 183 
J 0
(-1102 2075);
DISPLAY 0.638298 (-1102 2075);
PAINT MONO (-1102 2075);
FORCEPROP 2 LAST CDS_LIB standard
J 0
(-850 2075);
PAINT MONO (-850 2075);
DISPLAY INVISIBLE (-850 2075);
FORCEPROP 1 LAST OFFPAGE TRUE
J 0
(-525 1950);
DISPLAY 0.872340 (-525 1950);
PAINT GREEN (-525 1950);
DISPLAY INVISIBLE (-525 1950);
FORCEPROP 1 LAST COMMENT_BODY TRUE
J 0
(-725 1975);
DISPLAY 0.872340 (-725 1975);
PAINT GREEN (-725 1975);
DISPLAY INVISIBLE (-725 1975);
FORCEPROP 2 LAST PATH I62
J 0
(-1125 2125);
DISPLAY 1.021277 (-1125 2125);
DISPLAY INVISIBLE (-1125 2125);
FORCEADD OFFPAGE..1
(-850 2025);
FORCEPROP 2 LAST $XR0 183 
J 0
(-1102 2025);
DISPLAY 0.638298 (-1102 2025);
PAINT MONO (-1102 2025);
FORCEPROP 2 LAST CDS_LIB standard
J 0
(-850 2025);
PAINT MONO (-850 2025);
DISPLAY INVISIBLE (-850 2025);
FORCEPROP 1 LAST OFFPAGE TRUE
J 0
(-525 1900);
DISPLAY 0.872340 (-525 1900);
PAINT GREEN (-525 1900);
DISPLAY INVISIBLE (-525 1900);
FORCEPROP 1 LAST COMMENT_BODY TRUE
J 0
(-725 1925);
DISPLAY 0.872340 (-725 1925);
PAINT GREEN (-725 1925);
DISPLAY INVISIBLE (-725 1925);
FORCEPROP 2 LAST PATH I63
J 0
(-1125 2075);
DISPLAY 1.021277 (-1125 2075);
DISPLAY INVISIBLE (-1125 2075);
FORCEADD OFFPAGE..1
(-850 1825);
FORCEPROP 2 LAST $XR0 132 
J 0
(-1102 1825);
DISPLAY 0.638298 (-1102 1825);
PAINT MONO (-1102 1825);
FORCEPROP 2 LAST CDS_LIB standard
J 0
(-850 1825);
PAINT MONO (-850 1825);
DISPLAY INVISIBLE (-850 1825);
FORCEPROP 1 LAST OFFPAGE TRUE
J 0
(-525 1700);
DISPLAY 0.872340 (-525 1700);
PAINT GREEN (-525 1700);
DISPLAY INVISIBLE (-525 1700);
FORCEPROP 1 LAST COMMENT_BODY TRUE
J 0
(-725 1725);
DISPLAY 0.872340 (-725 1725);
PAINT GREEN (-725 1725);
DISPLAY INVISIBLE (-725 1725);
FORCEPROP 2 LAST PATH I64
J 0
(-1125 1875);
DISPLAY 1.021277 (-1125 1875);
DISPLAY INVISIBLE (-1125 1875);
FORCEADD OFFPAGE..1
(-850 1875);
FORCEPROP 2 LAST $XR0 132 
J 0
(-1102 1875);
DISPLAY 0.638298 (-1102 1875);
PAINT MONO (-1102 1875);
FORCEPROP 2 LAST CDS_LIB standard
J 0
(-850 1875);
PAINT MONO (-850 1875);
DISPLAY INVISIBLE (-850 1875);
FORCEPROP 1 LAST OFFPAGE TRUE
J 0
(-525 1750);
DISPLAY 0.872340 (-525 1750);
PAINT GREEN (-525 1750);
DISPLAY INVISIBLE (-525 1750);
FORCEPROP 1 LAST COMMENT_BODY TRUE
J 0
(-725 1775);
DISPLAY 0.872340 (-725 1775);
PAINT GREEN (-725 1775);
DISPLAY INVISIBLE (-725 1775);
FORCEPROP 2 LAST PATH I65
J 0
(-1125 1925);
DISPLAY 1.021277 (-1125 1925);
DISPLAY INVISIBLE (-1125 1925);
FORCEADD OFFPAGE..1
(-850 1975);
FORCEPROP 2 LAST $XR0 183 
J 0
(-1102 1975);
DISPLAY 0.638298 (-1102 1975);
PAINT MONO (-1102 1975);
FORCEPROP 2 LAST CDS_LIB standard
J 0
(-850 1975);
PAINT MONO (-850 1975);
DISPLAY INVISIBLE (-850 1975);
FORCEPROP 1 LAST OFFPAGE TRUE
J 0
(-525 1850);
DISPLAY 0.872340 (-525 1850);
PAINT GREEN (-525 1850);
DISPLAY INVISIBLE (-525 1850);
FORCEPROP 1 LAST COMMENT_BODY TRUE
J 0
(-725 1875);
DISPLAY 0.872340 (-725 1875);
PAINT GREEN (-725 1875);
DISPLAY INVISIBLE (-725 1875);
FORCEPROP 2 LAST PATH I66
J 0
(-1125 2025);
DISPLAY 1.021277 (-1125 2025);
DISPLAY INVISIBLE (-1125 2025);
FORCEADD OFFPAGE..1
(-850 1725);
FORCEPROP 2 LAST $XR0 183 
J 0
(-1102 1725);
DISPLAY 0.638298 (-1102 1725);
PAINT MONO (-1102 1725);
FORCEPROP 2 LAST CDS_LIB standard
J 0
(-850 1725);
PAINT MONO (-850 1725);
DISPLAY INVISIBLE (-850 1725);
FORCEPROP 1 LAST OFFPAGE TRUE
J 0
(-525 1600);
DISPLAY 0.872340 (-525 1600);
PAINT GREEN (-525 1600);
DISPLAY INVISIBLE (-525 1600);
FORCEPROP 1 LAST COMMENT_BODY TRUE
J 0
(-725 1625);
DISPLAY 0.872340 (-725 1625);
PAINT GREEN (-725 1625);
DISPLAY INVISIBLE (-725 1625);
FORCEPROP 2 LAST PATH I67
J 0
(-1125 1775);
DISPLAY 1.021277 (-1125 1775);
DISPLAY INVISIBLE (-1125 1775);
FORCEADD OFFPAGE..1
(-850 3025);
FORCEPROP 2 LAST $XR0 182 
J 0
(-1102 3025);
DISPLAY 0.638298 (-1102 3025);
PAINT MONO (-1102 3025);
FORCEPROP 2 LAST CDS_LIB standard
J 0
(-850 3025);
PAINT MONO (-850 3025);
DISPLAY INVISIBLE (-850 3025);
FORCEPROP 1 LAST OFFPAGE TRUE
J 0
(-525 2900);
DISPLAY 0.872340 (-525 2900);
PAINT GREEN (-525 2900);
DISPLAY INVISIBLE (-525 2900);
FORCEPROP 1 LAST COMMENT_BODY TRUE
J 0
(-725 2925);
DISPLAY 0.872340 (-725 2925);
PAINT GREEN (-725 2925);
DISPLAY INVISIBLE (-725 2925);
FORCEPROP 2 LAST PATH I68
J 0
(-1125 3075);
DISPLAY 1.021277 (-1125 3075);
DISPLAY INVISIBLE (-1125 3075);
FORCEADD UNIVERSAL_POWER..1
(25 3750);
FORCEPROP 3 LASTPIN (25 3700) SIG_NAME P1V05_PCH_AUX\g
J 0
(35 3710);
DISPLAY 0.659574 (35 3710);
PAINT MONO (35 3710);
DISPLAY INVISIBLE (35 3710);
FORCEPROP 1 LAST HDL_POWER P1V05_PCH_AUX
J 1
(25 3800);
DISPLAY 0.872340 (25 3800);
PAINT GREEN (25 3800);
FORCEPROP 2 LAST CDS_LIB logical_power
J 0
(25 3750);
PAINT MONO (25 3750);
DISPLAY INVISIBLE (25 3750);
FORCEPROP 1 LAST PATH I69
J 0
(75 3775);
DISPLAY 0.872340 (75 3775);
PAINT AQUA (75 3775);
DISPLAY INVISIBLE (75 3775);
FORCEADD Q_RES..1
(1625 3125);
FORCEPROP 1 LAST PART_NUMBER CS11002FB07
J 0
(1775 3100);
DISPLAY 0.319149 (1775 3100);
DISPLAY INVISIBLE (1775 3100);
FORCEPROP 1 LAST PACK_TYPE 0402LF
J 0
(1925 3125);
DISPLAY 0.510638 (1925 3125);
FORCEPROP 1 LAST WATTAGE 1/16W
J 2
(1950 3075);
DISPLAY 0.319149 (1950 3075);
FORCEPROP 1 LAST MATERIAL CHIP
J 0
(1775 3075);
DISPLAY 0.319149 (1775 3075);
FORCEPROP 1 LAST VALUE 100
J 2
(1825 3125);
DISPLAY 0.510638 (1825 3125);
FORCEPROP 1 LAST TOLERANCE 1%
J 0
(1850 3125);
DISPLAY 0.510638 (1850 3125);
FORCEPROP 1 LAST $LOCATION R776
J 0
(1425 3125);
DISPLAY 0.638298 (1425 3125);
FORCEPROP 1 LASTPIN (1525 3125) $PN 1
J 0
(1537 3137);
DISPLAY 0.787234 (1537 3137);
FORCEPROP 1 LASTPIN (1725 3125) $PN 2
J 0
(1687 3137);
DISPLAY 0.787234 (1687 3137);
FORCEPROP 2 LAST CDS_LIB pure_quanta
J 0
(1625 3125);
PAINT MONO (1625 3125);
DISPLAY INVISIBLE (1625 3125);
FORCEPROP 1 LAST PATH I7
J 0
(1575 3275);
DISPLAY 0.978723 (1575 3275);
PAINT WHITE (1575 3275);
DISPLAY INVISIBLE (1575 3275);
FORCEPROP 2 LAST CDS_LOCATION R776
J 0
(1575 3325);
DISPLAY 1.021277 (1575 3325);
DISPLAY INVISIBLE (1575 3325);
FORCEPROP 2 LAST $SEC 1
J 0
(1575 3325);
DISPLAY 0.680851 (1575 3325);
PAINT MONO (1575 3325);
DISPLAY INVISIBLE (1575 3325);
FORCEPROP 2 LAST CDS_SEC 1
J 0
(1575 3325);
DISPLAY 1.021277 (1575 3325);
DISPLAY INVISIBLE (1575 3325);
FORCEADD Q_RES..1
(-1650 3075);
FORCEPROP 1 LAST PART_NUMBER CS01002FB07
J 0
(-1525 3050);
DISPLAY 0.319149 (-1525 3050);
DISPLAY INVISIBLE (-1525 3050);
FORCEPROP 1 LAST PACK_TYPE 0402LF
J 0
(-1375 3075);
DISPLAY 0.510638 (-1375 3075);
FORCEPROP 1 LAST MATERIAL CHIP
J 0
(-1525 3025);
DISPLAY 0.319149 (-1525 3025);
FORCEPROP 1 LAST WATTAGE 1/16W
J 2
(-1375 3025);
DISPLAY 0.319149 (-1375 3025);
FORCEPROP 1 LAST TOLERANCE 1%
J 0
(-1450 3075);
DISPLAY 0.510638 (-1450 3075);
FORCEPROP 1 LAST VALUE 10
J 2
(-1475 3075);
DISPLAY 0.510638 (-1475 3075);
FORCEPROP 1 LAST $LOCATION R763
J 0
(-1850 3075);
DISPLAY 0.638298 (-1850 3075);
FORCEPROP 1 LASTPIN (-1750 3075) $PN 1
J 0
(-1738 3087);
DISPLAY 0.787234 (-1738 3087);
FORCEPROP 1 LASTPIN (-1550 3075) $PN 2
J 0
(-1588 3087);
DISPLAY 0.787234 (-1588 3087);
FORCEPROP 2 LAST CDS_LIB pure_quanta
J 0
(-1650 3075);
PAINT MONO (-1650 3075);
DISPLAY INVISIBLE (-1650 3075);
FORCEPROP 1 LAST PATH I70
J 0
(-1700 3225);
DISPLAY 0.978723 (-1700 3225);
PAINT WHITE (-1700 3225);
DISPLAY INVISIBLE (-1700 3225);
FORCEPROP 2 LAST CDS_LOCATION R763
J 0
(-1700 3275);
DISPLAY 1.021277 (-1700 3275);
DISPLAY INVISIBLE (-1700 3275);
FORCEPROP 2 LAST $SEC 1
J 0
(-1700 3275);
DISPLAY 0.680851 (-1700 3275);
PAINT MONO (-1700 3275);
DISPLAY INVISIBLE (-1700 3275);
FORCEPROP 2 LAST CDS_SEC 1
J 0
(-1700 3275);
DISPLAY 1.021277 (-1700 3275);
DISPLAY INVISIBLE (-1700 3275);
FORCEADD Q_RES..1
(-1650 3125);
FORCEPROP 1 LAST PART_NUMBER CS00002JB13
J 0
(-1525 3150);
DISPLAY 0.319149 (-1525 3150);
DISPLAY INVISIBLE (-1525 3150);
FORCEPROP 1 LAST PACK_TYPE 0402LF
J 0
(-1375 3125);
DISPLAY 0.510638 (-1375 3125);
FORCEPROP 1 LAST TOLERANCE 5%
J 0
(-1475 3125);
DISPLAY 0.510638 (-1475 3125);
FORCEPROP 1 LAST VALUE 0
J 2
(-1500 3125);
DISPLAY 0.510638 (-1500 3125);
FORCEPROP 1 LAST MATERIAL CHIP
J 0
(-1525 3175);
DISPLAY 0.319149 (-1525 3175);
FORCEPROP 1 LAST WATTAGE 1/16W
J 2
(-1350 3175);
DISPLAY 0.319149 (-1350 3175);
FORCEPROP 1 LAST $LOCATION R762
J 0
(-1850 3125);
DISPLAY 0.638298 (-1850 3125);
FORCEPROP 1 LASTPIN (-1750 3125) $PN 1
J 0
(-1738 3137);
DISPLAY 0.787234 (-1738 3137);
FORCEPROP 1 LASTPIN (-1550 3125) $PN 2
J 0
(-1588 3137);
DISPLAY 0.787234 (-1588 3137);
FORCEPROP 2 LAST CDS_LIB pure_quanta
J 0
(-1650 3125);
PAINT MONO (-1650 3125);
DISPLAY INVISIBLE (-1650 3125);
FORCEPROP 1 LAST PATH I71
J 0
(-1700 3275);
DISPLAY 0.978723 (-1700 3275);
PAINT WHITE (-1700 3275);
DISPLAY INVISIBLE (-1700 3275);
FORCEPROP 2 LAST CDS_LOCATION R762
J 0
(-1700 3325);
DISPLAY 1.021277 (-1700 3325);
DISPLAY INVISIBLE (-1700 3325);
FORCEPROP 2 LAST $SEC 1
J 0
(-1700 3325);
DISPLAY 0.680851 (-1700 3325);
PAINT MONO (-1700 3325);
DISPLAY INVISIBLE (-1700 3325);
FORCEPROP 2 LAST CDS_SEC 1
J 0
(-1700 3325);
DISPLAY 1.021277 (-1700 3325);
DISPLAY INVISIBLE (-1700 3325);
FORCEADD Q_RES..1
(-1650 1925);
FORCEPROP 1 LAST PART_NUMBER CS00002JB13
J 0
(-1525 1950);
DISPLAY 0.319149 (-1525 1950);
DISPLAY INVISIBLE (-1525 1950);
FORCEPROP 1 LAST PACK_TYPE 0402LF
J 0
(-1375 1925);
DISPLAY 0.510638 (-1375 1925);
FORCEPROP 1 LAST MATERIAL CHIP
J 0
(-1525 1975);
DISPLAY 0.319149 (-1525 1975);
FORCEPROP 1 LAST TOLERANCE 5%
J 0
(-1475 1925);
DISPLAY 0.510638 (-1475 1925);
FORCEPROP 1 LAST VALUE 0
J 2
(-1500 1925);
DISPLAY 0.510638 (-1500 1925);
FORCEPROP 1 LAST WATTAGE 1/16W
J 2
(-1350 1975);
DISPLAY 0.319149 (-1350 1975);
FORCEPROP 1 LAST $LOCATION R765
J 0
(-1850 1925);
DISPLAY 0.638298 (-1850 1925);
FORCEPROP 1 LASTPIN (-1750 1925) $PN 1
J 0
(-1738 1937);
DISPLAY 0.787234 (-1738 1937);
FORCEPROP 1 LASTPIN (-1550 1925) $PN 2
J 0
(-1588 1937);
DISPLAY 0.787234 (-1588 1937);
FORCEPROP 2 LAST CDS_LIB pure_quanta
J 0
(-1650 1925);
PAINT MONO (-1650 1925);
DISPLAY INVISIBLE (-1650 1925);
FORCEPROP 1 LAST PATH I74
J 0
(-1700 2075);
DISPLAY 0.978723 (-1700 2075);
PAINT WHITE (-1700 2075);
DISPLAY INVISIBLE (-1700 2075);
FORCEPROP 2 LAST CDS_LOCATION R765
J 0
(-1700 2125);
DISPLAY 1.021277 (-1700 2125);
DISPLAY INVISIBLE (-1700 2125);
FORCEPROP 2 LAST $SEC 1
J 0
(-1700 2125);
DISPLAY 0.680851 (-1700 2125);
PAINT MONO (-1700 2125);
DISPLAY INVISIBLE (-1700 2125);
FORCEPROP 2 LAST CDS_SEC 1
J 0
(-1700 2125);
DISPLAY 1.021277 (-1700 2125);
DISPLAY INVISIBLE (-1700 2125);
FORCEADD OFFPAGE..2
R 2
(-2700 1925);
FORCEPROP 2 LAST $XR1 182 
J 0
(-3105 1925);
DISPLAY 0.638298 (-3105 1925);
PAINT MONO (-3105 1925);
FORCEPROP 2 LAST $XR0 134 
J 0
(-2985 1925);
DISPLAY 0.638298 (-2985 1925);
PAINT MONO (-2985 1925);
FORCEPROP 2 LAST CDS_LIB standard
J 0
(-2700 1925);
PAINT MONO (-2700 1925);
DISPLAY INVISIBLE (-2700 1925);
FORCEPROP 1 LAST OFFPAGE TRUE
J 2
(-3025 1800);
DISPLAY 0.872340 (-3025 1800);
DISPLAY INVISIBLE (-3025 1800);
FORCEPROP 1 LAST COMMENT_BODY TRUE
J 2
(-2655 1830);
DISPLAY 0.872340 (-2655 1830);
PAINT GREEN (-2655 1830);
DISPLAY INVISIBLE (-2655 1830);
FORCEPROP 2 LAST PATH I76
J 0
(-2650 2000);
DISPLAY 1.021277 (-2650 2000);
DISPLAY INVISIBLE (-2650 2000);
FORCEADD OFFPAGE..2
R 2
(-2700 3075);
FORCEPROP 2 LAST $XR1 132 
J 0
(-3105 3075);
DISPLAY 0.638298 (-3105 3075);
PAINT MONO (-3105 3075);
FORCEPROP 2 LAST $XR0 239 
J 0
(-2985 3075);
DISPLAY 0.638298 (-2985 3075);
PAINT MONO (-2985 3075);
FORCEPROP 2 LAST CDS_LIB standard
J 0
(-2700 3075);
PAINT MONO (-2700 3075);
DISPLAY INVISIBLE (-2700 3075);
FORCEPROP 1 LAST OFFPAGE TRUE
J 2
(-3025 2950);
DISPLAY 0.872340 (-3025 2950);
DISPLAY INVISIBLE (-3025 2950);
FORCEPROP 1 LAST COMMENT_BODY TRUE
J 2
(-2655 2980);
DISPLAY 0.872340 (-2655 2980);
PAINT GREEN (-2655 2980);
DISPLAY INVISIBLE (-2655 2980);
FORCEPROP 2 LAST PATH I78
J 0
(-2650 3150);
DISPLAY 1.021277 (-2650 3150);
DISPLAY INVISIBLE (-2650 3150);
FORCEADD OFFPAGE..2
R 2
(-2700 3125);
FORCEPROP 2 LAST $XR4 44 
J 0
(-3405 3125);
DISPLAY 0.638298 (-3405 3125);
PAINT MONO (-3405 3125);
FORCEPROP 2 LAST $XR3 13 
J 0
(-3315 3125);
DISPLAY 0.638298 (-3315 3125);
PAINT MONO (-3315 3125);
FORCEPROP 2 LAST $XR2 182 
J 0
(-3225 3125);
DISPLAY 0.638298 (-3225 3125);
PAINT MONO (-3225 3125);
FORCEPROP 2 LAST $XR1 134 
J 0
(-3105 3125);
DISPLAY 0.638298 (-3105 3125);
PAINT MONO (-3105 3125);
FORCEPROP 2 LAST $XR0 131 
J 0
(-2985 3125);
DISPLAY 0.638298 (-2985 3125);
PAINT MONO (-2985 3125);
FORCEPROP 2 LAST CDS_LIB standard
J 0
(-2700 3125);
PAINT MONO (-2700 3125);
DISPLAY INVISIBLE (-2700 3125);
FORCEPROP 1 LAST OFFPAGE TRUE
J 2
(-3025 3000);
DISPLAY 0.872340 (-3025 3000);
DISPLAY INVISIBLE (-3025 3000);
FORCEPROP 1 LAST COMMENT_BODY TRUE
J 2
(-2655 3030);
DISPLAY 0.872340 (-2655 3030);
PAINT GREEN (-2655 3030);
DISPLAY INVISIBLE (-2655 3030);
FORCEPROP 2 LAST PATH I79
J 0
(-2650 3200);
DISPLAY 1.021277 (-2650 3200);
DISPLAY INVISIBLE (-2650 3200);
FORCEADD OFFPAGE..2
(2725 3075);
FORCEPROP 2 LAST $XR0 131 
J 0
(2914 3075);
DISPLAY 0.638298 (2914 3075);
PAINT MONO (2914 3075);
FORCEPROP 2 LAST CDS_LIB standard
J 0
(2725 3075);
PAINT MONO (2725 3075);
DISPLAY INVISIBLE (2725 3075);
FORCEPROP 1 LAST OFFPAGE TRUE
J 0
(3050 2950);
DISPLAY 0.872340 (3050 2950);
PAINT GREEN (3050 2950);
DISPLAY INVISIBLE (3050 2950);
FORCEPROP 1 LAST COMMENT_BODY TRUE
J 0
(2680 2980);
DISPLAY 0.872340 (2680 2980);
PAINT GREEN (2680 2980);
DISPLAY INVISIBLE (2680 2980);
FORCEPROP 2 LAST PATH I8
J 0
(2900 3150);
DISPLAY 1.021277 (2900 3150);
DISPLAY INVISIBLE (2900 3150);
FORCEADD OFFPAGE..2
R 2
(-850 2775);
FORCEPROP 2 LAST $XR0 131 
J 0
(-1105 2775);
DISPLAY 0.638298 (-1105 2775);
PAINT MONO (-1105 2775);
FORCEPROP 2 LAST CDS_LIB standard
J 0
(-850 2775);
PAINT MONO (-850 2775);
DISPLAY INVISIBLE (-850 2775);
FORCEPROP 1 LAST OFFPAGE TRUE
J 2
(-1175 2650);
DISPLAY 0.872340 (-1175 2650);
DISPLAY INVISIBLE (-1175 2650);
FORCEPROP 1 LAST COMMENT_BODY TRUE
J 2
(-805 2680);
DISPLAY 0.872340 (-805 2680);
PAINT GREEN (-805 2680);
DISPLAY INVISIBLE (-805 2680);
FORCEPROP 2 LAST PATH I80
J 0
(-800 2850);
DISPLAY 1.021277 (-800 2850);
DISPLAY INVISIBLE (-800 2850);
FORCEADD OFFPAGE..2
R 2
(-850 2825);
FORCEPROP 2 LAST $XR0 131 
J 0
(-1105 2825);
DISPLAY 0.638298 (-1105 2825);
PAINT MONO (-1105 2825);
FORCEPROP 2 LAST CDS_LIB standard
J 0
(-850 2825);
PAINT MONO (-850 2825);
DISPLAY INVISIBLE (-850 2825);
FORCEPROP 1 LAST OFFPAGE TRUE
J 2
(-1175 2700);
DISPLAY 0.872340 (-1175 2700);
DISPLAY INVISIBLE (-1175 2700);
FORCEPROP 1 LAST COMMENT_BODY TRUE
J 2
(-805 2730);
DISPLAY 0.872340 (-805 2730);
PAINT GREEN (-805 2730);
DISPLAY INVISIBLE (-805 2730);
FORCEPROP 2 LAST PATH I81
J 0
(-800 2900);
DISPLAY 1.021277 (-800 2900);
DISPLAY INVISIBLE (-800 2900);
FORCEADD Q_RES..1
(-1650 2925);
FORCEPROP 1 LAST PART_NUMBER CS00002JB13
J 0
(-1525 2950);
DISPLAY 0.319149 (-1525 2950);
DISPLAY INVISIBLE (-1525 2950);
FORCEPROP 1 LAST PACK_TYPE 0402LF
J 0
(-1375 2925);
DISPLAY 0.510638 (-1375 2925);
FORCEPROP 1 LAST TOLERANCE 5%
J 0
(-1475 2925);
DISPLAY 0.510638 (-1475 2925);
FORCEPROP 1 LAST VALUE 0
J 2
(-1500 2925);
DISPLAY 0.510638 (-1500 2925);
FORCEPROP 1 LAST WATTAGE 1/16W
J 2
(-1350 2975);
DISPLAY 0.319149 (-1350 2975);
FORCEPROP 1 LAST MATERIAL CHIP
J 0
(-1525 2975);
DISPLAY 0.319149 (-1525 2975);
FORCEPROP 1 LAST $LOCATION R764
J 0
(-1850 2925);
DISPLAY 0.638298 (-1850 2925);
FORCEPROP 1 LASTPIN (-1750 2925) $PN 1
J 0
(-1738 2937);
DISPLAY 0.787234 (-1738 2937);
FORCEPROP 1 LASTPIN (-1550 2925) $PN 2
J 0
(-1588 2937);
DISPLAY 0.787234 (-1588 2937);
FORCEPROP 2 LAST CDS_LIB pure_quanta
J 0
(-1650 2925);
PAINT MONO (-1650 2925);
DISPLAY INVISIBLE (-1650 2925);
FORCEPROP 1 LAST PATH I83
J 0
(-1700 3075);
DISPLAY 0.978723 (-1700 3075);
PAINT WHITE (-1700 3075);
DISPLAY INVISIBLE (-1700 3075);
FORCEPROP 2 LAST CDS_LOCATION R764
J 0
(-1700 3125);
DISPLAY 1.021277 (-1700 3125);
DISPLAY INVISIBLE (-1700 3125);
FORCEPROP 2 LAST $SEC 1
J 0
(-1700 3125);
DISPLAY 0.680851 (-1700 3125);
PAINT MONO (-1700 3125);
DISPLAY INVISIBLE (-1700 3125);
FORCEPROP 2 LAST CDS_SEC 1
J 0
(-1700 3125);
DISPLAY 1.021277 (-1700 3125);
DISPLAY INVISIBLE (-1700 3125);
FORCEADD OFFPAGE..4
(2725 3125);
FORCEPROP 2 LAST $XR1 239 
J 0
(3031 3125);
DISPLAY 0.638298 (3031 3125);
PAINT MONO (3031 3125);
FORCEPROP 2 LAST $XR0 132 
J 0
(2911 3125);
DISPLAY 0.638298 (2911 3125);
PAINT MONO (2911 3125);
FORCEPROP 2 LAST CDS_LIB standard
J 0
(2725 3125);
PAINT MONO (2725 3125);
DISPLAY INVISIBLE (2725 3125);
FORCEPROP 1 LAST OFFPAGE TRUE
J 0
(3050 3000);
DISPLAY 1.170213 (3050 3000);
PAINT GREEN (3050 3000);
DISPLAY INVISIBLE (3050 3000);
FORCEPROP 1 LAST COMMENT_BODY TRUE
J 0
(2700 3025);
DISPLAY 1.170213 (2700 3025);
PAINT GREEN (2700 3025);
DISPLAY INVISIBLE (2700 3025);
FORCEPROP 2 LAST PATH I85
J 0
(3050 3175);
DISPLAY 1.021277 (3050 3175);
DISPLAY INVISIBLE (3050 3175);
FORCEADD OFFPAGE..4
(1575 2175);
FORCEPROP 2 LAST $XR0 131 
J 0
(1761 2175);
DISPLAY 0.638298 (1761 2175);
PAINT MONO (1761 2175);
FORCEPROP 2 LAST CDS_LIB standard
J 0
(1575 2175);
PAINT MONO (1575 2175);
DISPLAY INVISIBLE (1575 2175);
FORCEPROP 1 LAST OFFPAGE TRUE
J 0
(1900 2050);
DISPLAY 1.170213 (1900 2050);
PAINT GREEN (1900 2050);
DISPLAY INVISIBLE (1900 2050);
FORCEPROP 1 LAST COMMENT_BODY TRUE
J 0
(1550 2075);
DISPLAY 1.170213 (1550 2075);
PAINT GREEN (1550 2075);
DISPLAY INVISIBLE (1550 2075);
FORCEPROP 2 LAST PATH I86
J 0
(1900 2225);
DISPLAY 1.021277 (1900 2225);
DISPLAY INVISIBLE (1900 2225);
FORCEADD OFFPAGE..4
(1575 2025);
FORCEPROP 2 LAST $XR0 131 
J 0
(1761 2025);
DISPLAY 0.638298 (1761 2025);
PAINT MONO (1761 2025);
FORCEPROP 2 LAST CDS_LIB standard
J 0
(1575 2025);
PAINT MONO (1575 2025);
DISPLAY INVISIBLE (1575 2025);
FORCEPROP 1 LAST OFFPAGE TRUE
J 0
(1900 1900);
DISPLAY 1.170213 (1900 1900);
PAINT GREEN (1900 1900);
DISPLAY INVISIBLE (1900 1900);
FORCEPROP 1 LAST COMMENT_BODY TRUE
J 0
(1550 1925);
DISPLAY 1.170213 (1550 1925);
PAINT GREEN (1550 1925);
DISPLAY INVISIBLE (1550 1925);
FORCEPROP 2 LAST PATH I87
J 0
(1900 2075);
DISPLAY 1.021277 (1900 2075);
DISPLAY INVISIBLE (1900 2075);
FORCEADD OFFPAGE..3
(1575 1975);
FORCEPROP 2 LAST $XR0 131 
J 0
(1789 1975);
DISPLAY 0.638298 (1789 1975);
PAINT MONO (1789 1975);
FORCEPROP 2 LAST CDS_LIB standard
J 0
(1575 1975);
PAINT MONO (1575 1975);
DISPLAY INVISIBLE (1575 1975);
FORCEPROP 1 LAST OFFPAGE TRUE
J 0
(1900 1850);
DISPLAY 0.872340 (1900 1850);
DISPLAY INVISIBLE (1900 1850);
FORCEPROP 1 LAST COMMENT_BODY TRUE
J 0
(1525 1875);
DISPLAY 0.872340 (1525 1875);
PAINT GREEN (1525 1875);
DISPLAY INVISIBLE (1525 1875);
FORCEPROP 2 LAST PATH I88
J 0
(1950 2025);
DISPLAY 1.021277 (1950 2025);
DISPLAY INVISIBLE (1950 2025);
FORCEADD OFFPAGE..2
(3700 2275);
FORCEPROP 2 LAST $XR1 239 
J 0
(4009 2275);
DISPLAY 0.638298 (4009 2275);
PAINT MONO (4009 2275);
FORCEPROP 2 LAST $XR0 203 
J 0
(3889 2275);
DISPLAY 0.638298 (3889 2275);
PAINT MONO (3889 2275);
FORCEPROP 2 LAST CDS_LIB standard
J 0
(3700 2275);
DISPLAY INVISIBLE (3700 2275);
FORCEPROP 1 LAST OFFPAGE TRUE
J 0
(4025 2150);
DISPLAY 0.872340 (4025 2150);
PAINT GREEN (4025 2150);
DISPLAY INVISIBLE (4025 2150);
FORCEPROP 1 LAST COMMENT_BODY TRUE
J 0
(3655 2180);
DISPLAY 0.872340 (3655 2180);
PAINT GREEN (3655 2180);
DISPLAY INVISIBLE (3655 2180);
FORCEPROP 2 LAST PATH I89
J 0
(3875 2350);
DISPLAY 1.021277 (3875 2350);
DISPLAY INVISIBLE (3875 2350);
FORCEADD OFFPAGE..2
(2725 2975);
FORCEPROP 2 LAST $XR1 239 
J 0
(3034 2975);
DISPLAY 0.638298 (3034 2975);
PAINT MONO (3034 2975);
FORCEPROP 2 LAST $XR0 132 
J 0
(2914 2975);
DISPLAY 0.638298 (2914 2975);
PAINT MONO (2914 2975);
FORCEPROP 2 LAST CDS_LIB standard
J 0
(2725 2975);
DISPLAY INVISIBLE (2725 2975);
FORCEPROP 1 LAST OFFPAGE TRUE
J 0
(3050 2850);
DISPLAY 0.872340 (3050 2850);
PAINT GREEN (3050 2850);
DISPLAY INVISIBLE (3050 2850);
FORCEPROP 1 LAST COMMENT_BODY TRUE
J 0
(2680 2880);
DISPLAY 0.872340 (2680 2880);
PAINT GREEN (2680 2880);
DISPLAY INVISIBLE (2680 2880);
FORCEPROP 2 LAST PATH I9
J 0
(2900 3050);
DISPLAY 1.021277 (2900 3050);
DISPLAY INVISIBLE (2900 3050);
FORCEADD OFFPAGE..2
(3700 2225);
FORCEPROP 2 LAST $XR1 45 
J 0
(3979 2225);
DISPLAY 0.638298 (3979 2225);
PAINT MONO (3979 2225);
FORCEPROP 2 LAST $XR0 14 
J 0
(3889 2225);
DISPLAY 0.638298 (3889 2225);
PAINT MONO (3889 2225);
FORCEPROP 2 LAST CDS_LIB standard
J 0
(3700 2225);
DISPLAY INVISIBLE (3700 2225);
FORCEPROP 1 LAST OFFPAGE TRUE
J 0
(4025 2100);
DISPLAY 0.872340 (4025 2100);
PAINT GREEN (4025 2100);
DISPLAY INVISIBLE (4025 2100);
FORCEPROP 1 LAST COMMENT_BODY TRUE
J 0
(3655 2130);
DISPLAY 0.872340 (3655 2130);
PAINT GREEN (3655 2130);
DISPLAY INVISIBLE (3655 2130);
FORCEPROP 2 LAST PATH I91
J 0
(3875 2300);
DISPLAY 1.021277 (3875 2300);
DISPLAY INVISIBLE (3875 2300);
FORCEADD Q_RES..1
(2500 2225);
FORCEPROP 1 LAST PART_NUMBER CS04992FB07
J 0
(2600 2200);
DISPLAY 0.404255 (2600 2200);
DISPLAY INVISIBLE (2600 2200);
FORCEPROP 1 LAST MATERIAL CHIP
J 0
(2600 2175);
DISPLAY 0.404255 (2600 2175);
FORCEPROP 1 LAST WATTAGE 1/16W
J 2
(2800 2175);
DISPLAY 0.404255 (2800 2175);
FORCEPROP 1 LAST PACK_TYPE 0402LF
J 0
(2800 2225);
DISPLAY 0.510638 (2800 2225);
FORCEPROP 1 LAST TOLERANCE 1%
J 0
(2725 2225);
DISPLAY 0.510638 (2725 2225);
FORCEPROP 1 LAST VALUE 49.9
J 2
(2700 2225);
DISPLAY 0.510638 (2700 2225);
FORCEPROP 1 LAST $LOCATION R780
J 0
(2300 2225);
DISPLAY 0.638298 (2300 2225);
FORCEPROP 1 LASTPIN (2400 2225) $PN 1
J 0
(2412 2237);
DISPLAY 0.787234 (2412 2237);
FORCEPROP 1 LASTPIN (2600 2225) $PN 2
J 0
(2562 2237);
DISPLAY 0.787234 (2562 2237);
FORCEPROP 2 LAST CDS_LIB pure_quanta
J 0
(2500 2225);
PAINT MONO (2500 2225);
DISPLAY INVISIBLE (2500 2225);
FORCEPROP 1 LAST PATH I92
J 0
(2450 2375);
DISPLAY 0.978723 (2450 2375);
PAINT WHITE (2450 2375);
DISPLAY INVISIBLE (2450 2375);
FORCEPROP 2 LAST CDS_LOCATION R780
J 0
(2450 2425);
DISPLAY 1.021277 (2450 2425);
DISPLAY INVISIBLE (2450 2425);
FORCEPROP 2 LAST $SEC 1
J 0
(2450 2425);
DISPLAY 0.680851 (2450 2425);
PAINT MONO (2450 2425);
DISPLAY INVISIBLE (2450 2425);
FORCEPROP 2 LAST CDS_SEC 1
J 0
(2450 2425);
DISPLAY 1.021277 (2450 2425);
DISPLAY INVISIBLE (2450 2425);
FORCEADD UNIVERSAL_POWER..1
(2200 2725);
FORCEPROP 3 LASTPIN (2200 2675) SIG_NAME PVNN_TERM_CPU0\g
J 0
(2210 2685);
DISPLAY 0.659574 (2210 2685);
PAINT MONO (2210 2685);
DISPLAY INVISIBLE (2210 2685);
FORCEPROP 1 LAST HDL_POWER PVNN_TERM_CPU0
J 1
(2200 2775);
DISPLAY 0.702128 (2200 2775);
PAINT GREEN (2200 2775);
FORCEPROP 2 LAST CDS_LIB logical_power
J 0
(2200 2725);
PAINT MONO (2200 2725);
DISPLAY INVISIBLE (2200 2725);
FORCEPROP 1 LAST PATH I94
J 0
(2250 2750);
DISPLAY 0.872340 (2250 2750);
PAINT AQUA (2250 2750);
DISPLAY INVISIBLE (2250 2750);
FORCEADD Q_RES..2
(2200 2525);
FORCEPROP 1 LAST PART_NUMBER CS11502FB07
J 0
(2240 2400);
DISPLAY 0.404255 (2240 2400);
DISPLAY INVISIBLE (2240 2400);
FORCEPROP 1 LAST TOLERANCE 1%
J 0
(2245 2550);
DISPLAY 0.510638 (2245 2550);
FORCEPROP 1 LAST PACK_TYPE 0402LF
J 0
(2240 2350);
DISPLAY 0.510638 (2240 2350);
FORCEPROP 1 LAST MATERIAL CHIP
J 0
(2240 2450);
DISPLAY 0.510638 (2240 2450);
FORCEPROP 1 LAST WATTAGE 1/16W
J 0
(2240 2500);
DISPLAY 0.510638 (2240 2500);
FORCEPROP 1 LAST VALUE 150
J 0
(2245 2600);
DISPLAY 0.510638 (2245 2600);
FORCEPROP 1 LAST $LOCATION R779
J 0
(2245 2650);
DISPLAY 0.978723 (2245 2650);
FORCEPROP 1 LASTPIN (2200 2625) $PN 1
J 0
(2205 2587);
DISPLAY 0.787234 (2205 2587);
FORCEPROP 1 LASTPIN (2200 2425) $PN 2
J 0
(2205 2435);
DISPLAY 0.787234 (2205 2435);
FORCEPROP 2 LAST CDS_LIB pure_quanta
J 0
(2200 2525);
PAINT MONO (2200 2525);
DISPLAY INVISIBLE (2200 2525);
FORCEPROP 1 LAST PATH I95
J 0
(2250 2700);
DISPLAY 0.978723 (2250 2700);
PAINT WHITE (2250 2700);
DISPLAY INVISIBLE (2250 2700);
FORCEPROP 2 LAST CDS_LOCATION R779
J 0
(2250 2750);
DISPLAY 1.021277 (2250 2750);
DISPLAY INVISIBLE (2250 2750);
FORCEPROP 2 LAST $SEC 1
J 0
(2250 2750);
DISPLAY 0.680851 (2250 2750);
PAINT MONO (2250 2750);
DISPLAY INVISIBLE (2250 2750);
FORCEPROP 2 LAST CDS_SEC 1
J 0
(2250 2750);
DISPLAY 1.021277 (2250 2750);
DISPLAY INVISIBLE (2250 2750);
FORCEADD Q_CAP..1
(2225 2050);
FORCEPROP 1 LAST PART_NUMBER CH4104K1B00
J 0
(2275 1900);
DISPLAY 0.510638 (2275 1900);
DISPLAY INVISIBLE (2275 1900);
FORCEPROP 1 LAST VALUE 0.1UF
J 0
(2275 2100);
DISPLAY 0.510638 (2275 2100);
FORCEPROP 1 LAST TOLERANCE 10%
J 0
(2275 2000);
DISPLAY 0.510638 (2275 2000);
FORCEPROP 1 LAST VOLTAGE 25V
J 0
(2275 2050);
DISPLAY 0.510638 (2275 2050);
FORCEPROP 1 LAST MATERIAL X7R
J 0
(2275 1950);
DISPLAY 0.510638 (2275 1950);
FORCEPROP 1 LAST PACK_TYPE 0402
J 0
(2275 1850);
DISPLAY 0.510638 (2275 1850);
FORCEPROP 1 LAST $LOCATION C552
J 0
(2275 2150);
DISPLAY 0.638298 (2275 2150);
FORCEPROP 1 LASTPIN (2225 2150) $PN 1
J 0
(2235 2130);
DISPLAY 0.787234 (2235 2130);
FORCEPROP 1 LASTPIN (2225 1950) $PN 2
J 0
(2235 1930);
DISPLAY 0.787234 (2235 1930);
FORCEPROP 2 LAST CDS_LIB pure_quanta
J 0
(2225 2050);
PAINT MONO (2225 2050);
DISPLAY INVISIBLE (2225 2050);
FORCEPROP 1 LAST PATH I96
J 0
(2275 2200);
DISPLAY 0.978723 (2275 2200);
PAINT WHITE (2275 2200);
DISPLAY INVISIBLE (2275 2200);
FORCEPROP 2 LAST CDS_LOCATION C552
J 0
(2275 2250);
DISPLAY 1.021277 (2275 2250);
DISPLAY INVISIBLE (2275 2250);
FORCEPROP 2 LAST $SEC 1
J 0
(2275 2250);
DISPLAY 0.680851 (2275 2250);
PAINT MONO (2275 2250);
DISPLAY INVISIBLE (2275 2250);
FORCEPROP 2 LAST CDS_SEC 1
J 0
(2275 2250);
DISPLAY 1.021277 (2275 2250);
DISPLAY INVISIBLE (2275 2250);
FORCEADD UNIVERSAL_GND..1
(2225 1800);
FORCEPROP 3 LASTPIN (2225 1850) SIG_NAME GND\g
J 0
(2235 1860);
DISPLAY 0.659574 (2235 1860);
PAINT MONO (2235 1860);
DISPLAY INVISIBLE (2235 1860);
FORCEPROP 2 LAST CDS_LIB logical_power
J 0
(2225 1800);
PAINT MONO (2225 1800);
DISPLAY INVISIBLE (2225 1800);
FORCEPROP 1 LAST HDL_POWER GND
J 1
(2250 1725);
DISPLAY 0.872340 (2250 1725);
PAINT GREEN (2250 1725);
DISPLAY INVISIBLE (2250 1725);
FORCEPROP 1 LAST PATH I97
J 0
(2300 1800);
DISPLAY 0.872340 (2300 1800);
PAINT AQUA (2300 1800);
DISPLAY INVISIBLE (2300 1800);
FORCEADD UNIVERSAL_GND..1
(875 3300);
FORCEPROP 3 LASTPIN (875 3350) SIG_NAME GND\g
J 0
(885 3360);
DISPLAY 0.659574 (885 3360);
PAINT MONO (885 3360);
DISPLAY INVISIBLE (885 3360);
FORCEPROP 2 LAST CDS_LIB logical_power
J 0
(875 3300);
PAINT MONO (875 3300);
DISPLAY INVISIBLE (875 3300);
FORCEPROP 1 LAST HDL_POWER GND
J 1
(900 3225);
DISPLAY 0.872340 (900 3225);
PAINT GREEN (900 3225);
DISPLAY INVISIBLE (900 3225);
FORCEPROP 1 LAST PATH I98
J 0
(950 3300);
DISPLAY 0.872340 (950 3300);
PAINT AQUA (950 3300);
DISPLAY INVISIBLE (950 3300);
FORCEADD Q_CAP..1
(875 3500);
FORCEPROP 1 LAST PART_NUMBER CH5104KEB02
J 0
(925 3350);
DISPLAY 0.510638 (925 3350);
DISPLAY INVISIBLE (925 3350);
FORCEPROP 1 LAST TOLERANCE 10%
J 0
(925 3450);
DISPLAY 0.510638 (925 3450);
FORCEPROP 1 LAST MATERIAL X6S
J 0
(925 3400);
DISPLAY 0.510638 (925 3400);
FORCEPROP 1 LAST PACK_TYPE C0402
J 0
(925 3300);
DISPLAY 0.510638 (925 3300);
FORCEPROP 1 LAST VALUE 1UF
J 0
(925 3550);
DISPLAY 0.510638 (925 3550);
FORCEPROP 1 LAST VOLTAGE 25V
J 0
(925 3500);
DISPLAY 0.510638 (925 3500);
FORCEPROP 1 LAST $LOCATION C550
J 0
(925 3600);
DISPLAY 0.978723 (925 3600);
FORCEPROP 1 LASTPIN (875 3600) $PN 1
J 0
(885 3580);
DISPLAY 0.787234 (885 3580);
FORCEPROP 1 LASTPIN (875 3400) $PN 2
J 0
(885 3380);
DISPLAY 0.787234 (885 3380);
FORCEPROP 2 LAST CDS_LIB pure_quanta
J 0
(875 3500);
PAINT MONO (875 3500);
DISPLAY INVISIBLE (875 3500);
FORCEPROP 1 LAST PATH I99
J 0
(925 3650);
DISPLAY 0.978723 (925 3650);
PAINT WHITE (925 3650);
DISPLAY INVISIBLE (925 3650);
FORCEPROP 2 LAST CDS_LOCATION C550
J 0
(925 3700);
DISPLAY 1.021277 (925 3700);
DISPLAY INVISIBLE (925 3700);
FORCEPROP 2 LAST $SEC 1
J 0
(925 3700);
DISPLAY 0.680851 (925 3700);
PAINT MONO (925 3700);
DISPLAY INVISIBLE (925 3700);
FORCEPROP 2 LAST CDS_SEC 1
J 0
(925 3700);
DISPLAY 1.021277 (925 3700);
DISPLAY INVISIBLE (925 3700);
FORCEADD DNS..2
(-120 -280);
PAINT RED (-120 -280);
FORCEPROP 2 LAST CDS_LIB mstr_misc
J 0
(-120 -280);
PAINT MONO (-120 -280);
DISPLAY INVISIBLE (-120 -280);
FORCEPROP 1 LAST COMMENT_BODY TRUE
J 0
(-120 -280);
DISPLAY INVISIBLE (-120 -280);
FORCEADD QUANTA_TITLE_BLOCK_C..1
(5250 -1950);
FORCEPROP 0 LAST CDS_CON_LAST_MODIFIED Fri Aug 25 14:01:51 2023
J 0
(3365 -1935);
PAINT MONO (3365 -1935);
DISPLAY INVISIBLE (3365 -1935);
FORCEPROP 1 LAST CUSTOM_TXT_CDS <CON_LAST_MODIFIED>
J 0
(3365 -1935);
DISPLAY 0.978723 (3365 -1935);
FORCEPROP 2 LAST CUSTOM_TXT_CDS <XR_PAGE_TITLE>
J 0
(-2640 3300);
DISPLAY 0.638298 (-2640 3300);
PAINT PINK (-2640 3300);
DISPLAY INVISIBLE (-2640 3300);
FORCEPROP 1 LAST CUSTOM_TXT_CDS <NAME_2>
J 0
(2075 -1900);
FORCEPROP 1 LAST CUSTOM_TXT_CDS <NAME_1>
J 0
(2075 -1775);
FORCEPROP 1 LAST CUSTOM_TXT_CDS <Q_NUMBER>
J 0
(3847 -1847);
DISPLAY 1.212766 (3847 -1847);
FORCEPROP 1 LAST CUSTOM_TXT_CDS <Q_PROJ>
J 0
(2868 -1848);
DISPLAY 1.212766 (2868 -1848);
FORCEPROP 1 LAST CUSTOM_TXT_CDS <Q_REV>
J 0
(5066 -1847);
DISPLAY 1.212766 (5066 -1847);
FORCEPROP 1 LAST CUSTOM_TXT_CDS <CON_PAGE_NUM> OF <CON_TOTAL_PAGES>
J 0
(4804 -1932);
DISPLAY 0.978723 (4804 -1932);
FORCEPROP 1 LAST Q_TITLE SPR & PCH - DEBUG PORT (1/3)
J 0
(-4016 -1949);
DISPLAY 2.446809 (-4016 -1949);
PAINT GREEN (-4016 -1949);
FORCEPROP 1 LAST Q_DEPT 
J 1
(1487 -1901);
DISPLAY 1.957447 (1487 -1901);
PAINT GREEN (1487 -1901);
FORCEPROP 2 LAST CDS_XR_PAGE_TITLE CR-131 : @S9S_MB_2U_LIB.S9S_MB_2U(SCH_1):PAGE131
J 0
(-2640 3300);
DISPLAY 0.638298 (-2640 3300);
PAINT PINK (-2640 3300);
DISPLAY INVISIBLE (-2640 3300);
FORCEPROP 2 LAST CDS_LIB pure_quanta
J 0
(5250 -1950);
PAINT MONO (5250 -1950);
DISPLAY INVISIBLE (5250 -1950);
FORCEPROP 1 LAST CDS_LMAN_SYM_OUTLINE -9475,6775,100,-125
J 0
(5250 -1950);
DISPLAY 0.468085 (5250 -1950);
PAINT GREEN (5250 -1950);
DISPLAY INVISIBLE (5250 -1950);
FORCEPROP 2 LAST PAGE_BORDER TRUE
J 0
(-2640 3300);
DISPLAY 0.638298 (-2640 3300);
PAINT PINK (-2640 3300);
DISPLAY INVISIBLE (-2640 3300);
FORCEPROP 1 LAST COMMENT_BODY TRUE
J 0
(5262 -1963);
DISPLAY 0.978723 (5262 -1963);
PAINT GREEN (5262 -1963);
DISPLAY INVISIBLE (5262 -1963);
WIRE 16 -1 (-125 0)(-125 -50);
WIRE 16 -1 (2200 2675)(2200 2625);
WIRE 16 -1 (1825 1725)(1825 1675);
WIRE 16 -1 (725 3650)(725 3700);
WIRE 16 -1 (725 2925)(725 3650);
WIRE 16 -1 (875 3650)(725 3650);
WIRE 16 -1 (25 3650)(25 3700);
WIRE 16 -1 (25 3175)(25 3650);
WIRE 16 -1 (25 3650)(-125 3650);
WIRE 16 -1 (1750 2675)(1750 2625);
WIRE 16 -1 (2650 2550)(2650 2475);
WIRE 16 -1 (725 1625)(725 1550);
WIRE 16 -1 (725 1675)(725 1625);
WIRE 16 -1 (625 1625)(725 1625);
WIRE 16 -1 (25 1550)(25 1625);
WIRE 16 -1 (100 -1325)(100 -1425);
WIRE 16 -1 (-125 -1325)(-125 -1425);
WIRE 16 -1 (725 -1325)(725 -1425);
WIRE 16 -1 (-125 3400)(-125 3350);
WIRE 16 -1 (1825 1425)(1825 1375);
WIRE 16 -1 (2225 1850)(2225 1950);
WIRE 16 -1 (875 3400)(875 3350);
WIRE 16 -1 (-375 750)(525 750);
FORCEPROP 0 LAST CDS_PHYS_NET_NAME PD_PIROM_CPU0_ADDR0
J 0
(-185 798);
PAINT MONO (-185 798);
DISPLAY INVISIBLE (-185 798);
FORCEPROP 2 LAST SIG_NAME SMB_HOST_3V3AUX_SCL_R4
J 0
(-135 760);
DISPLAY 0.510638 (-135 760);
PAINT WHITE (-135 760);
WIRE 16 -1 (-375 700)(525 700);
FORCEPROP 0 LAST CDS_PHYS_NET_NAME PD_PIROM_CPU0_ADDR0
J 0
(-185 748);
PAINT MONO (-185 748);
DISPLAY INVISIBLE (-185 748);
FORCEPROP 2 LAST SIG_NAME SMB_HOST_3V3AUX_SDA_R4
J 0
(-135 710);
DISPLAY 0.510638 (-135 710);
PAINT WHITE (-135 710);
WIRE 16 -1 (725 750)(1675 750);
FORCEPROP 0 LAST CDS_PHYS_NET_NAME PD_PIROM_CPU0_ADDR0
J 0
(915 798);
PAINT MONO (915 798);
DISPLAY INVISIBLE (915 798);
FORCEPROP 2 LAST SIG_NAME SMB_HOST_3V3AUX_XDP_R_SCL
J 0
(1065 760);
DISPLAY 0.510638 (1065 760);
PAINT WHITE (1065 760);
WIRE 16 -1 (725 700)(1675 700);
FORCEPROP 0 LAST CDS_PHYS_NET_NAME PD_PIROM_CPU0_ADDR0
J 0
(915 748);
PAINT MONO (915 748);
DISPLAY INVISIBLE (915 748);
FORCEPROP 2 LAST SIG_NAME SMB_HOST_3V3AUX_XDP_R_SDA
J 0
(1065 710);
DISPLAY 0.510638 (1065 710);
PAINT WHITE (1065 710);
WIRE 16 -1 (625 2325)(1750 2325);
FORCEPROP 0 LAST CDS_PHYS_NET_NAME PD_PIROM_CPU0_ADDR0
J 0
(815 2373);
PAINT MONO (815 2373);
DISPLAY INVISIBLE (815 2373);
FORCEPROP 2 LAST SIG_NAME JTAG_DBP_BOOT_HALT_N
J 0
(865 2335);
DISPLAY 0.510638 (865 2335);
PAINT WHITE (865 2335);
WIRE 16 -1 (3650 2325)(1750 2325);
WIRE 16 -1 (1750 2425)(1750 2325);
WIRE 16 -1 (625 2475)(1525 2475);
FORCEPROP 0 LAST CDS_PHYS_NET_NAME NC_DBP_P34
J 0
(815 2523);
PAINT MONO (815 2523);
DISPLAY INVISIBLE (815 2523);
FORCEPROP 2 LAST SIG_NAME NC_DBP_P30
J 0
(865 2485);
DISPLAY 0.510638 (865 2485);
PAINT WHITE (865 2485);
WIRE 16 -1 (625 2525)(1525 2525);
FORCEPROP 0 LAST CDS_PHYS_NET_NAME NC_DBP_P34
J 0
(815 2573);
PAINT MONO (815 2573);
DISPLAY INVISIBLE (815 2573);
FORCEPROP 2 LAST SIG_NAME NC_DBP_P28
J 0
(865 2535);
DISPLAY 0.510638 (865 2535);
PAINT WHITE (865 2535);
WIRE 16 -1 (625 2575)(1525 2575);
FORCEPROP 0 LAST CDS_PHYS_NET_NAME NC_DBP_P34
J 0
(815 2623);
PAINT MONO (815 2623);
DISPLAY INVISIBLE (815 2623);
FORCEPROP 2 LAST SIG_NAME NC_DBP_P26
J 0
(865 2585);
DISPLAY 0.510638 (865 2585);
PAINT WHITE (865 2585);
WIRE 16 -1 (625 2675)(1525 2675);
FORCEPROP 0 LAST CDS_PHYS_NET_NAME NC_DBP_P34
J 0
(815 2723);
PAINT MONO (815 2723);
DISPLAY INVISIBLE (815 2723);
FORCEPROP 2 LAST SIG_NAME NC_DBP_P22
J 0
(865 2685);
DISPLAY 0.510638 (865 2685);
PAINT WHITE (865 2685);
WIRE 16 -1 (625 2775)(1525 2775);
FORCEPROP 0 LAST CDS_PHYS_NET_NAME NC_DBP_P34
J 0
(815 2823);
PAINT MONO (815 2823);
DISPLAY INVISIBLE (815 2823);
FORCEPROP 2 LAST SIG_NAME NC_DBP_P18
J 0
(865 2785);
DISPLAY 0.510638 (865 2785);
PAINT WHITE (865 2785);
WIRE 16 -1 (2675 3125)(1725 3125);
FORCEPROP 2 LAST SIG_NAME JTAG_DBP_TDO
J 0
(2168 3129);
DISPLAY 0.553191 (2168 3129);
PAINT WHITE (2168 3129);
WIRE 16 -1 (625 3075)(2675 3075);
FORCEPROP 0 LAST CDS_PHYS_NET_NAME PD_PIROM_CPU0_ADDR0
J 0
(815 3123);
PAINT MONO (815 3123);
DISPLAY INVISIBLE (815 3123);
FORCEPROP 2 LAST SIG_NAME JTAG_RST_DBP_RST_CO_N
J 0
(865 3085);
DISPLAY 0.510638 (865 3085);
PAINT WHITE (865 3085);
WIRE 16 -1 (-125 3600)(-125 3650);
WIRE 16 -1 (25 3175)(125 3175);
FORCEPROP 0 LAST CDS_PHYS_NET_NAME P1V8_PCH_AUX
J 0
(75 3175);
PAINT MONO (75 3175);
DISPLAY INVISIBLE (75 3175);
FORCEPROP 0 LAST $PHYS_NET_NAME P1V8_PCH_AUX
J 0
(75 3222);
PAINT MONO (75 3222);
DISPLAY INVISIBLE (75 3222);
WIRE 16 -1 (25 1625)(125 1625);
WIRE 16 -1 (25 1625)(25 1675);
WIRE 16 -1 (25 1675)(125 1675);
WIRE 16 -1 (25 1675)(25 1775);
WIRE 16 -1 (25 1775)(125 1775);
FORCEPROP 0 LAST CDS_PHYS_NET_NAME GND
J 0
(75 1822);
PAINT MONO (75 1822);
DISPLAY INVISIBLE (75 1822);
FORCEPROP 0 LAST VOLTAGE 0
J 0
(75 1775);
PAINT MONO (75 1775);
DISPLAY INVISIBLE (75 1775);
FORCEPROP 0 LAST PHYS_NET_NAME GND
J 0
(75 1869);
PAINT MONO (75 1869);
DISPLAY INVISIBLE (75 1869);
WIRE 16 -1 (625 1925)(1600 1925);
WIRE 16 -1 (1600 1925)(1600 1675);
WIRE 16 -1 (1600 1675)(1825 1675);
WIRE 16 -1 (1825 1625)(1825 1675);
WIRE 16 -1 (625 2875)(725 2875);
WIRE 16 -1 (625 2825)(725 2825);
WIRE 16 -1 (725 2875)(725 2825);
WIRE 16 -1 (625 1775)(725 1775);
WIRE 16 -1 (725 1775)(725 2825);
WIRE 16 -1 (625 1725)(725 1725);
WIRE 16 -1 (725 1775)(725 1725);
WIRE 16 -1 (725 1725)(725 1675);
WIRE 16 -1 (625 1675)(725 1675);
WIRE 16 -1 (875 3600)(875 3650);
WIRE 16 -1 (625 2925)(725 2925);
FORCEPROP 0 LAST CDS_PHYS_NET_NAME P1V8_PCH_AUX
J 0
(675 2925);
PAINT MONO (675 2925);
DISPLAY INVISIBLE (675 2925);
FORCEPROP 0 LAST $PHYS_NET_NAME P1V8_PCH_AUX
J 0
(675 2972);
PAINT MONO (675 2972);
DISPLAY INVISIBLE (675 2972);
WIRE 16 -1 (-125 -50)(-125 -150);
WIRE 16 -1 (100 -50)(-125 -50);
WIRE 16 -1 (100 -150)(100 -50);
WIRE 16 -1 (300 -50)(100 -50);
WIRE 16 -1 (300 -150)(300 -50);
WIRE 16 -1 (125 2925)(-1550 2925);
FORCEPROP 0 LAST CDS_PHYS_NET_NAME PD_PIROM_CPU0_ADDR0
J 0
(-1360 2973);
PAINT MONO (-1360 2973);
DISPLAY INVISIBLE (-1360 2973);
FORCEPROP 2 LAST SIG_NAME JTAG_DBP_PRDY_R1_N
J 0
(-735 2935);
DISPLAY 0.510638 (-735 2935);
PAINT WHITE (-735 2935);
WIRE 16 -1 (125 3025)(-800 3025);
FORCEPROP 0 LAST CDS_PHYS_NET_NAME TRC_PCH_PTI1_CLK
J 0
(-610 3073);
PAINT MONO (-610 3073);
DISPLAY INVISIBLE (-610 3073);
FORCEPROP 2 LAST SIG_NAME JTAG_DBP_PMODE
J 0
(-735 3035);
DISPLAY 0.510638 (-735 3035);
PAINT WHITE (-735 3035);
WIRE 16 -1 (125 3075)(-1550 3075);
FORCEPROP 0 LAST CDS_PHYS_NET_NAME PD_PIROM_CPU0_ADDR0
J 0
(-1360 3123);
PAINT MONO (-1360 3123);
DISPLAY INVISIBLE (-1360 3123);
FORCEPROP 2 LAST SIG_NAME JTAG_DBP_TDI_R
J 0
(-735 3085);
DISPLAY 0.510638 (-735 3085);
PAINT WHITE (-735 3085);
WIRE 16 -1 (125 3125)(-1550 3125);
FORCEPROP 0 LAST CDS_PHYS_NET_NAME PD_PIROM_CPU0_ADDR0
J 0
(-1360 3173);
PAINT MONO (-1360 3173);
DISPLAY INVISIBLE (-1360 3173);
FORCEPROP 2 LAST SIG_NAME JTAG_DBP_CPU_GTL_TCK_R
J 0
(-735 3135);
DISPLAY 0.510638 (-735 3135);
PAINT WHITE (-735 3135);
WIRE 16 -1 (625 3175)(1525 3175);
FORCEPROP 0 LAST CDS_PHYS_NET_NAME PD_PIROM_CPU0_ADDR0
J 0
(815 3223);
PAINT MONO (815 3223);
DISPLAY INVISIBLE (815 3223);
FORCEPROP 2 LAST SIG_NAME JTAG_DBP_TMS_R
J 0
(865 3185);
DISPLAY 0.510638 (865 3185);
PAINT WHITE (865 3185);
WIRE 16 -1 (2650 2750)(2650 3025);
WIRE 16 -1 (625 3025)(2650 3025);
FORCEPROP 0 LAST CDS_PHYS_NET_NAME PD_PIROM_CPU0_ADDR0
J 0
(815 3073);
PAINT MONO (815 3073);
DISPLAY INVISIBLE (815 3073);
FORCEPROP 2 LAST SIG_NAME PD_TRST_P3
J 0
(865 3035);
DISPLAY 0.510638 (865 3035);
PAINT WHITE (865 3035);
WIRE 16 -1 (2225 2150)(2225 2225);
WIRE 16 -1 (2400 2225)(2225 2225);
WIRE 16 -1 (2225 2275)(2225 2225);
WIRE 16 -1 (2225 2275)(3650 2275);
FORCEPROP 2 LAST SIG_NAME FM_CPU_FBRK_DEBUG_N
J 0
(3018 2279);
DISPLAY 0.553191 (3018 2279);
PAINT WHITE (3018 2279);
WIRE 16 -1 (2200 2275)(2225 2275);
WIRE 16 -1 (2200 2425)(2200 2275);
WIRE 16 -1 (625 2275)(2200 2275);
FORCEPROP 0 LAST CDS_PHYS_NET_NAME PD_PIROM_CPU0_ADDR0
J 0
(815 2323);
PAINT MONO (815 2323);
DISPLAY INVISIBLE (815 2323);
WIRE 16 -1 (625 1875)(1525 1875);
FORCEPROP 0 LAST CDS_PHYS_NET_NAME PD_PIROM_CPU0_ADDR0
J 0
(815 1923);
PAINT MONO (815 1923);
DISPLAY INVISIBLE (815 1923);
FORCEPROP 2 LAST SIG_NAME NC_DBP_P54
J 0
(865 1885);
DISPLAY 0.510638 (865 1885);
PAINT WHITE (865 1885);
WIRE 16 -1 (625 1825)(1525 1825);
FORCEPROP 0 LAST CDS_PHYS_NET_NAME PD_PIROM_CPU0_ADDR0
J 0
(815 1873);
PAINT MONO (815 1873);
DISPLAY INVISIBLE (815 1873);
FORCEPROP 2 LAST SIG_NAME NC_DBP_P56
J 0
(865 1835);
DISPLAY 0.510638 (865 1835);
PAINT WHITE (865 1835);
WIRE 16 -1 (125 1825)(-800 1825);
FORCEPROP 0 LAST CDS_PHYS_NET_NAME PD_PIROM_CPU0_ADDR0
J 0
(-610 1873);
PAINT MONO (-610 1873);
DISPLAY INVISIBLE (-610 1873);
FORCEPROP 2 LAST SIG_NAME JTAG_DBP_CPU_HOOK8_MBP2_GTL_N
J 0
(-735 1835);
DISPLAY 0.510638 (-735 1835);
PAINT WHITE (-735 1835);
WIRE 16 -1 (125 1725)(-800 1725);
FORCEPROP 0 LAST CDS_PHYS_NET_NAME TRC_PCH_PTI1_CLK
J 0
(-610 1773);
PAINT MONO (-610 1773);
DISPLAY INVISIBLE (-610 1773);
FORCEPROP 2 LAST SIG_NAME JTAG_TRC_PCH_PTI1_CLK
J 0
(-735 1735);
DISPLAY 0.510638 (-735 1735);
PAINT WHITE (-735 1735);
WIRE 16 -1 (625 2025)(1525 2025);
FORCEPROP 0 LAST CDS_PHYS_NET_NAME PD_PIROM_CPU0_ADDR0
J 0
(815 2073);
PAINT MONO (815 2073);
DISPLAY INVISIBLE (815 2073);
FORCEPROP 2 LAST SIG_NAME SMB_HOST_3V3AUX_XDP_R_SCL
J 0
(865 2035);
DISPLAY 0.510638 (865 2035);
PAINT WHITE (865 2035);
WIRE 16 -1 (625 1975)(1525 1975);
FORCEPROP 0 LAST CDS_PHYS_NET_NAME PD_PIROM_CPU0_ADDR0
J 0
(815 2023);
PAINT MONO (815 2023);
DISPLAY INVISIBLE (815 2023);
FORCEPROP 2 LAST SIG_NAME SMB_HOST_3V3AUX_XDP_R_SDA
J 0
(865 1985);
DISPLAY 0.510638 (865 1985);
PAINT WHITE (865 1985);
WIRE 16 -1 (625 2075)(1525 2075);
FORCEPROP 0 LAST CDS_PHYS_NET_NAME PD_PIROM_CPU0_ADDR0
J 0
(815 2123);
PAINT MONO (815 2123);
DISPLAY INVISIBLE (815 2123);
FORCEPROP 2 LAST SIG_NAME NC_DBP_P46
J 0
(865 2085);
DISPLAY 0.510638 (865 2085);
PAINT WHITE (865 2085);
WIRE 16 -1 (625 2125)(1525 2125);
FORCEPROP 0 LAST CDS_PHYS_NET_NAME PD_PIROM_CPU0_ADDR0
J 0
(815 2173);
PAINT MONO (815 2173);
DISPLAY INVISIBLE (815 2173);
FORCEPROP 2 LAST SIG_NAME NC_DBP_P44
J 0
(865 2135);
DISPLAY 0.510638 (865 2135);
PAINT WHITE (865 2135);
WIRE 16 -1 (625 2225)(1525 2225);
FORCEPROP 0 LAST CDS_PHYS_NET_NAME PD_PIROM_CPU0_ADDR0
J 0
(815 2273);
PAINT MONO (815 2273);
DISPLAY INVISIBLE (815 2273);
FORCEPROP 2 LAST SIG_NAME JTAG_DBP_POWER_BTN_N
J 0
(865 2235);
DISPLAY 0.510638 (865 2235);
PAINT WHITE (865 2235);
WIRE 16 -1 (625 2175)(1525 2175);
FORCEPROP 0 LAST CDS_PHYS_NET_NAME PD_PIROM_CPU0_ADDR0
J 0
(815 2223);
PAINT MONO (815 2223);
DISPLAY INVISIBLE (815 2223);
FORCEPROP 2 LAST SIG_NAME JTAG_RST_DBP_RSMRST_N
J 0
(865 2185);
DISPLAY 0.510638 (865 2185);
PAINT WHITE (865 2185);
WIRE 16 -1 (625 2625)(1525 2625);
FORCEPROP 0 LAST CDS_PHYS_NET_NAME NC_DBP_P34
J 0
(815 2673);
PAINT MONO (815 2673);
DISPLAY INVISIBLE (815 2673);
FORCEPROP 2 LAST SIG_NAME NC_DBP_P24
J 0
(865 2635);
DISPLAY 0.510638 (865 2635);
PAINT WHITE (865 2635);
WIRE 16 -1 (625 2425)(1525 2425);
FORCEPROP 0 LAST CDS_PHYS_NET_NAME PD_PIROM_CPU0_ADDR0
J 0
(815 2473);
PAINT MONO (815 2473);
DISPLAY INVISIBLE (815 2473);
FORCEPROP 2 LAST SIG_NAME NC_DBP_P32
J 0
(865 2435);
DISPLAY 0.510638 (865 2435);
PAINT WHITE (865 2435);
WIRE 16 -1 (625 2375)(1525 2375);
FORCEPROP 0 LAST CDS_PHYS_NET_NAME PD_PIROM_CPU0_ADDR0
J 0
(815 2423);
PAINT MONO (815 2423);
DISPLAY INVISIBLE (815 2423);
FORCEPROP 2 LAST SIG_NAME NC_DBP_P34
J 0
(865 2385);
DISPLAY 0.510638 (865 2385);
PAINT WHITE (865 2385);
WIRE 16 -1 (3650 2225)(2600 2225);
FORCEPROP 2 LAST SIG_NAME FM_CPU_FBRK_DEBUG_R_N
J 0
(3018 2229);
DISPLAY 0.553191 (3018 2229);
PAINT WHITE (3018 2229);
WIRE 16 -1 (625 3125)(1525 3125);
FORCEPROP 0 LAST CDS_PHYS_NET_NAME PD_PIROM_CPU0_ADDR0
J 0
(815 3173);
PAINT MONO (815 3173);
DISPLAY INVISIBLE (815 3173);
FORCEPROP 2 LAST SIG_NAME JTAG_DBP_TDO_R
J 0
(865 3135);
DISPLAY 0.510638 (865 3135);
PAINT WHITE (865 3135);
WIRE 16 -1 (125 2975)(-800 2975);
FORCEPROP 0 LAST CDS_PHYS_NET_NAME TRC_PCH_PTI1_CLK
J 0
(-610 3023);
PAINT MONO (-610 3023);
DISPLAY INVISIBLE (-610 3023);
FORCEPROP 2 LAST SIG_NAME NC_MIPI60_P9
J 0
(-735 2985);
DISPLAY 0.510638 (-735 2985);
PAINT WHITE (-735 2985);
WIRE 16 -1 (625 2975)(1525 2975);
FORCEPROP 0 LAST CDS_PHYS_NET_NAME PD_PIROM_CPU0_ADDR0
J 0
(815 3023);
PAINT MONO (815 3023);
DISPLAY INVISIBLE (815 3023);
FORCEPROP 2 LAST SIG_NAME JTAG_DBP_PREQ_N_R
J 0
(865 2985);
DISPLAY 0.510638 (865 2985);
PAINT WHITE (865 2985);
WIRE 16 -1 (125 2875)(-800 2875);
FORCEPROP 0 LAST CDS_PHYS_NET_NAME TRC_PCH_PTI1_CLK
J 0
(-610 2923);
PAINT MONO (-610 2923);
DISPLAY INVISIBLE (-610 2923);
FORCEPROP 2 LAST SIG_NAME JTAG_TRC_PCH_PTI0_CLK
J 0
(-735 2885);
DISPLAY 0.510638 (-735 2885);
PAINT WHITE (-735 2885);
WIRE 16 -1 (125 2825)(-800 2825);
FORCEPROP 0 LAST CDS_PHYS_NET_NAME PD_PIROM_CPU0_ADDR0
J 0
(-610 2873);
PAINT MONO (-610 2873);
DISPLAY INVISIBLE (-610 2873);
FORCEPROP 2 LAST SIG_NAME JTAG_DBP_PCH_DEBUG_CONSENT_N
J 0
(-735 2835);
DISPLAY 0.510638 (-735 2835);
PAINT WHITE (-735 2835);
WIRE 16 -1 (125 2775)(-800 2775);
FORCEPROP 0 LAST CDS_PHYS_NET_NAME PD_PIROM_CPU0_ADDR0
J 0
(-610 2823);
PAINT MONO (-610 2823);
DISPLAY INVISIBLE (-610 2823);
FORCEPROP 2 LAST SIG_NAME JTAG_DBP_PRESENT_R_N
J 0
(-735 2785);
DISPLAY 0.510638 (-735 2785);
PAINT WHITE (-735 2785);
WIRE 16 -1 (125 2725)(-800 2725);
FORCEPROP 0 LAST CDS_PHYS_NET_NAME TRC_PCH_PTI<0>
J 0
(-610 2773);
PAINT MONO (-610 2773);
DISPLAY INVISIBLE (-610 2773);
FORCEPROP 2 LAST SIG_NAME JTAG_TRC_PCH_PTI<0>
J 0
(-735 2735);
DISPLAY 0.510638 (-735 2735);
PAINT WHITE (-735 2735);
WIRE 16 -1 (625 2725)(1525 2725);
FORCEPROP 0 LAST CDS_PHYS_NET_NAME NC_DBP_P34
J 0
(815 2773);
PAINT MONO (815 2773);
DISPLAY INVISIBLE (815 2773);
FORCEPROP 2 LAST SIG_NAME NC_DBP_P20
J 0
(865 2735);
DISPLAY 0.510638 (865 2735);
PAINT WHITE (865 2735);
WIRE 16 -1 (125 2675)(-800 2675);
FORCEPROP 0 LAST CDS_PHYS_NET_NAME TRC_PCH_PTI<1>
J 0
(-610 2723);
PAINT MONO (-610 2723);
DISPLAY INVISIBLE (-610 2723);
FORCEPROP 2 LAST SIG_NAME JTAG_TRC_PCH_PTI<1>
J 0
(-735 2685);
DISPLAY 0.510638 (-735 2685);
PAINT WHITE (-735 2685);
WIRE 16 -1 (125 2625)(-800 2625);
FORCEPROP 0 LAST CDS_PHYS_NET_NAME TRC_PCH_PTI<2>
J 0
(-610 2673);
PAINT MONO (-610 2673);
DISPLAY INVISIBLE (-610 2673);
FORCEPROP 2 LAST SIG_NAME JTAG_TRC_PCH_PTI<2>
J 0
(-735 2635);
DISPLAY 0.510638 (-735 2635);
PAINT WHITE (-735 2635);
WIRE 16 -1 (125 2575)(-800 2575);
FORCEPROP 0 LAST CDS_PHYS_NET_NAME TRC_PCH_PTI<3>
J 0
(-610 2623);
PAINT MONO (-610 2623);
DISPLAY INVISIBLE (-610 2623);
FORCEPROP 2 LAST SIG_NAME JTAG_TRC_PCH_PTI<3>
J 0
(-735 2585);
DISPLAY 0.510638 (-735 2585);
PAINT WHITE (-735 2585);
WIRE 16 -1 (125 2525)(-800 2525);
FORCEPROP 0 LAST CDS_PHYS_NET_NAME TRC_PCH_PTI<4>
J 0
(-610 2573);
PAINT MONO (-610 2573);
DISPLAY INVISIBLE (-610 2573);
FORCEPROP 2 LAST SIG_NAME JTAG_TRC_PCH_PTI<4>
J 0
(-735 2535);
DISPLAY 0.510638 (-735 2535);
PAINT WHITE (-735 2535);
WIRE 16 -1 (125 2475)(-800 2475);
FORCEPROP 0 LAST CDS_PHYS_NET_NAME TRC_PCH_PTI<5>
J 0
(-610 2523);
PAINT MONO (-610 2523);
DISPLAY INVISIBLE (-610 2523);
FORCEPROP 2 LAST SIG_NAME JTAG_TRC_PCH_PTI<5>
J 0
(-735 2485);
DISPLAY 0.510638 (-735 2485);
PAINT WHITE (-735 2485);
WIRE 16 -1 (125 2425)(-800 2425);
FORCEPROP 0 LAST CDS_PHYS_NET_NAME TRC_PCH_PTI<6>
J 0
(-610 2473);
PAINT MONO (-610 2473);
DISPLAY INVISIBLE (-610 2473);
FORCEPROP 2 LAST SIG_NAME JTAG_TRC_PCH_PTI<6>
J 0
(-735 2435);
DISPLAY 0.510638 (-735 2435);
PAINT WHITE (-735 2435);
WIRE 16 -1 (125 2375)(-800 2375);
FORCEPROP 0 LAST CDS_PHYS_NET_NAME TRC_PCH_PTI<7>
J 0
(-610 2423);
PAINT MONO (-610 2423);
DISPLAY INVISIBLE (-610 2423);
FORCEPROP 2 LAST SIG_NAME JTAG_TRC_PCH_PTI<7>
J 0
(-735 2385);
DISPLAY 0.510638 (-735 2385);
PAINT WHITE (-735 2385);
WIRE 16 -1 (125 2325)(-800 2325);
FORCEPROP 0 LAST CDS_PHYS_NET_NAME TRC_PCH_PTI<8>
J 0
(-610 2373);
PAINT MONO (-610 2373);
DISPLAY INVISIBLE (-610 2373);
FORCEPROP 2 LAST SIG_NAME JTAG_TRC_PCH_PTI<8>
J 0
(-735 2335);
DISPLAY 0.510638 (-735 2335);
PAINT WHITE (-735 2335);
WIRE 16 -1 (125 2275)(-800 2275);
FORCEPROP 0 LAST CDS_PHYS_NET_NAME TRC_PCH_PTI<9>
J 0
(-610 2323);
PAINT MONO (-610 2323);
DISPLAY INVISIBLE (-610 2323);
FORCEPROP 2 LAST SIG_NAME JTAG_TRC_PCH_PTI<9>
J 0
(-735 2285);
DISPLAY 0.510638 (-735 2285);
PAINT WHITE (-735 2285);
WIRE 16 -1 (125 2225)(-800 2225);
FORCEPROP 0 LAST CDS_PHYS_NET_NAME TRC_PCH_PTI<10>
J 0
(-610 2273);
PAINT MONO (-610 2273);
DISPLAY INVISIBLE (-610 2273);
FORCEPROP 2 LAST SIG_NAME JTAG_TRC_PCH_PTI<10>
J 0
(-735 2235);
DISPLAY 0.510638 (-735 2235);
PAINT WHITE (-735 2235);
WIRE 16 -1 (125 2175)(-800 2175);
FORCEPROP 0 LAST CDS_PHYS_NET_NAME TRC_PCH_PTI<11>
J 0
(-610 2223);
PAINT MONO (-610 2223);
DISPLAY INVISIBLE (-610 2223);
FORCEPROP 2 LAST SIG_NAME JTAG_TRC_PCH_PTI<11>
J 0
(-735 2185);
DISPLAY 0.510638 (-735 2185);
PAINT WHITE (-735 2185);
WIRE 16 -1 (125 2125)(-800 2125);
FORCEPROP 0 LAST CDS_PHYS_NET_NAME TRC_PCH_PTI<12>
J 0
(-610 2173);
PAINT MONO (-610 2173);
DISPLAY INVISIBLE (-610 2173);
FORCEPROP 2 LAST SIG_NAME JTAG_TRC_PCH_PTI<12>
J 0
(-735 2135);
DISPLAY 0.510638 (-735 2135);
PAINT WHITE (-735 2135);
WIRE 16 -1 (125 2075)(-800 2075);
FORCEPROP 0 LAST CDS_PHYS_NET_NAME TRC_PCH_PTI<13>
J 0
(-610 2123);
PAINT MONO (-610 2123);
DISPLAY INVISIBLE (-610 2123);
FORCEPROP 2 LAST SIG_NAME JTAG_TRC_PCH_PTI<13>
J 0
(-735 2085);
DISPLAY 0.510638 (-735 2085);
PAINT WHITE (-735 2085);
WIRE 16 -1 (125 2025)(-800 2025);
FORCEPROP 0 LAST CDS_PHYS_NET_NAME TRC_PCH_PTI<14>
J 0
(-610 2073);
PAINT MONO (-610 2073);
DISPLAY INVISIBLE (-610 2073);
FORCEPROP 2 LAST SIG_NAME JTAG_TRC_PCH_PTI<14>
J 0
(-735 2035);
DISPLAY 0.510638 (-735 2035);
PAINT WHITE (-735 2035);
WIRE 16 -1 (125 1975)(-800 1975);
FORCEPROP 0 LAST CDS_PHYS_NET_NAME TRC_PCH_PTI<15>
J 0
(-610 2023);
PAINT MONO (-610 2023);
DISPLAY INVISIBLE (-610 2023);
FORCEPROP 2 LAST SIG_NAME JTAG_TRC_PCH_PTI<15>
J 0
(-735 1985);
DISPLAY 0.510638 (-735 1985);
PAINT WHITE (-735 1985);
WIRE 16 -1 (125 1925)(-1550 1925);
FORCEPROP 0 LAST CDS_PHYS_NET_NAME PD_PIROM_CPU0_ADDR0
J 0
(-1360 1973);
PAINT MONO (-1360 1973);
DISPLAY INVISIBLE (-1360 1973);
FORCEPROP 2 LAST SIG_NAME JTAG_DBP_TCK_R_TCK
J 0
(-660 1935);
DISPLAY 0.510638 (-660 1935);
PAINT WHITE (-660 1935);
WIRE 16 -1 (125 1875)(-800 1875);
FORCEPROP 0 LAST CDS_PHYS_NET_NAME PD_PIROM_CPU0_ADDR0
J 0
(-610 1923);
PAINT MONO (-610 1923);
DISPLAY INVISIBLE (-610 1923);
FORCEPROP 2 LAST SIG_NAME JTAG_DBP_CPU_HOOK9_MBP3_GTL_N
J 0
(-735 1885);
DISPLAY 0.510638 (-735 1885);
PAINT WHITE (-735 1885);
WIRE 16 -1 (2675 2975)(1725 2975);
FORCEPROP 2 LAST SIG_NAME JTAG_DBP_PREQ_N
J 0
(2168 2979);
DISPLAY 0.553191 (2168 2979);
PAINT WHITE (2168 2979);
WIRE 16 -1 (525 -950)(-1175 -950);
FORCEPROP 0 LAST CDS_PHYS_NET_NAME TRC_PCH_PTI1_CLK
J 0
(-985 -902);
PAINT MONO (-985 -902);
DISPLAY INVISIBLE (-985 -902);
FORCEPROP 2 LAST SIG_NAME JTAG_DBP_BOOT_HALT_N
J 0
(-1110 -940);
DISPLAY 0.638298 (-1110 -940);
PAINT WHITE (-1110 -940);
WIRE 16 -1 (525 -875)(-1175 -875);
FORCEPROP 0 LAST CDS_PHYS_NET_NAME TRC_PCH_PTI1_CLK
J 0
(-985 -827);
PAINT MONO (-985 -827);
DISPLAY INVISIBLE (-985 -827);
FORCEPROP 2 LAST SIG_NAME JTAG_RST_DBP_RSMRST_N
J 0
(-1110 -865);
DISPLAY 0.638298 (-1110 -865);
PAINT WHITE (-1110 -865);
WIRE 16 -1 (-1175 -800)(525 -800);
FORCEPROP 0 LAST CDS_PHYS_NET_NAME TRC_PCH_PTI1_CLK
J 0
(-985 -752);
PAINT MONO (-985 -752);
DISPLAY INVISIBLE (-985 -752);
FORCEPROP 2 LAST SIG_NAME JTAG_DBP_PCH_DEBUG_CONSENT_N
J 0
(-1110 -790);
DISPLAY 0.638298 (-1110 -790);
PAINT WHITE (-1110 -790);
WIRE 16 -1 (2000 -950)(725 -950);
FORCEPROP 0 LAST CDS_PHYS_NET_NAME TRC_PCH_PTI1_CLK
J 0
(915 -902);
PAINT MONO (915 -902);
DISPLAY INVISIBLE (915 -902);
FORCEPROP 2 LAST SIG_NAME FM_ADR_MODE0
J 0
(1190 -940);
DISPLAY 0.638298 (1190 -940);
PAINT WHITE (1190 -940);
WIRE 16 -1 (-125 -575)(-1175 -575);
FORCEPROP 0 LAST CDS_PHYS_NET_NAME TRC_PCH_PTI1_CLK
J 0
(-985 -527);
PAINT MONO (-985 -527);
DISPLAY INVISIBLE (-985 -527);
FORCEPROP 2 LAST SIG_NAME JTAG_DBP_POWER_BTN_N
J 0
(-1110 -565);
DISPLAY 0.638298 (-1110 -565);
PAINT WHITE (-1110 -565);
WIRE 16 -1 (-125 -575)(-125 -1125);
WIRE 16 -1 (-125 -350)(-125 -575);
WIRE 16 -1 (100 -650)(-1175 -650);
FORCEPROP 0 LAST CDS_PHYS_NET_NAME TRC_PCH_PTI1_CLK
J 0
(-985 -602);
PAINT MONO (-985 -602);
DISPLAY INVISIBLE (-985 -602);
FORCEPROP 2 LAST SIG_NAME JTAG_RST_DBP_RST_CO_N
J 0
(-1110 -640);
DISPLAY 0.638298 (-1110 -640);
PAINT WHITE (-1110 -640);
WIRE 16 -1 (100 -650)(100 -1125);
WIRE 16 -1 (100 -350)(100 -650);
WIRE 16 -1 (2000 -725)(725 -725);
FORCEPROP 0 LAST CDS_PHYS_NET_NAME TRC_PCH_PTI1_CLK
J 0
(915 -677);
PAINT MONO (915 -677);
DISPLAY INVISIBLE (915 -677);
FORCEPROP 2 LAST SIG_NAME FM_BMC_DBP_PRESENT_R_N
J 0
(1190 -715);
DISPLAY 0.638298 (1190 -715);
PAINT WHITE (1190 -715);
WIRE 16 -1 (2000 -800)(725 -800);
FORCEPROP 0 LAST CDS_PHYS_NET_NAME TRC_PCH_PTI1_CLK
J 0
(915 -752);
PAINT MONO (915 -752);
DISPLAY INVISIBLE (915 -752);
FORCEPROP 2 LAST SIG_NAME FM_PCH_CONSENT_STRAP_N
J 0
(1190 -790);
DISPLAY 0.638298 (1190 -790);
PAINT WHITE (1190 -790);
WIRE 16 -1 (2000 -875)(725 -875);
FORCEPROP 0 LAST CDS_PHYS_NET_NAME TRC_PCH_PTI1_CLK
J 0
(915 -827);
PAINT MONO (915 -827);
DISPLAY INVISIBLE (915 -827);
FORCEPROP 2 LAST SIG_NAME RST_RSMRST_PCH_N
J 0
(1190 -865);
DISPLAY 0.638298 (1190 -865);
PAINT WHITE (1190 -865);
WIRE 16 -1 (300 -725)(-1175 -725);
FORCEPROP 0 LAST CDS_PHYS_NET_NAME TRC_PCH_PTI1_CLK
J 0
(-985 -677);
PAINT MONO (-985 -677);
DISPLAY INVISIBLE (-985 -677);
FORCEPROP 2 LAST SIG_NAME JTAG_DBP_PRESENT_R_N
J 0
(-1110 -715);
DISPLAY 0.638298 (-1110 -715);
PAINT WHITE (-1110 -715);
WIRE 16 -1 (300 -350)(300 -725);
WIRE 16 -1 (525 -725)(300 -725);
WIRE 16 -1 (725 -1125)(725 -1025);
WIRE 16 -1 (2000 -1025)(725 -1025);
FORCEPROP 0 LAST CDS_PHYS_NET_NAME TRC_PCH_PTI1_CLK
J 0
(915 -977);
PAINT MONO (915 -977);
DISPLAY INVISIBLE (915 -977);
FORCEPROP 2 LAST SIG_NAME JTAG_DBP_CPU_GTL_TCK
J 0
(1190 -1015);
DISPLAY 0.638298 (1190 -1015);
PAINT WHITE (1190 -1015);
WIRE 16 -1 (-1750 1925)(-2650 1925);
FORCEPROP 0 LAST CDS_PHYS_NET_NAME JTAG_DBP_CPU_GTL_TCK
J 0
(-2460 1973);
PAINT MONO (-2460 1973);
DISPLAY INVISIBLE (-2460 1973);
FORCEPROP 2 LAST SIG_NAME JTAG_DBP_TCK_PCH
J 0
(-2560 1935);
DISPLAY 0.510638 (-2560 1935);
PAINT WHITE (-2560 1935);
WIRE 16 -1 (-1750 2925)(-2650 2925);
FORCEPROP 0 LAST CDS_PHYS_NET_NAME PD_PIROM_CPU0_ADDR0
J 0
(-2460 2973);
PAINT MONO (-2460 2973);
DISPLAY INVISIBLE (-2460 2973);
FORCEPROP 2 LAST SIG_NAME JTAG_DBP_PRDY_N
J 0
(-2560 2935);
DISPLAY 0.510638 (-2560 2935);
PAINT WHITE (-2560 2935);
WIRE 16 -1 (-1750 3125)(-2650 3125);
FORCEPROP 0 LAST CDS_PHYS_NET_NAME PD_PIROM_CPU0_ADDR0
J 0
(-2460 3173);
PAINT MONO (-2460 3173);
DISPLAY INVISIBLE (-2460 3173);
FORCEPROP 2 LAST SIG_NAME JTAG_DBP_CPU_GTL_TCK
J 0
(-2560 3135);
DISPLAY 0.510638 (-2560 3135);
PAINT WHITE (-2560 3135);
WIRE 16 -1 (-1750 3075)(-2650 3075);
FORCEPROP 0 LAST CDS_PHYS_NET_NAME PD_PIROM_CPU0_ADDR0
J 0
(-2460 3123);
PAINT MONO (-2460 3123);
DISPLAY INVISIBLE (-2460 3123);
FORCEPROP 2 LAST SIG_NAME JTAG_DBP_TDI
J 0
(-2560 3085);
DISPLAY 0.510638 (-2560 3085);
PAINT WHITE (-2560 3085);
WIRE 16 -1 (2675 3175)(1725 3175);
FORCEPROP 2 LAST SIG_NAME JTAG_DBP_TMS
J 0
(2168 3179);
DISPLAY 0.553191 (2168 3179);
PAINT WHITE (2168 3179);
DOT 1 (2200 2275);
DOT 1 (1825 1675);
DOT 1 (25 1625);
DOT 1 (725 1625);
DOT 1 (25 1675);
DOT 1 (725 1675);
DOT 1 (725 1725);
DOT 1 (725 1775);
DOT 1 (725 2825);
DOT 1 (100 -650);
DOT 1 (-125 -575);
DOT 1 (-125 -50);
DOT 1 (100 -50);
DOT 1 (300 -725);
DOT 1 (2225 2225);
DOT 1 (1750 2325);
DOT 1 (2225 2275);
DOT 1 (725 3650);
DOT 1 (25 3650);
QUIT
